# Altium SchDoc records: POWER.SchDoc
|HEADER=Protel for Windows - Schematic Capture Binary File Version 5.0|Weight=1641|MinorVersion=4
|RECORD=31|FontIdCount=7|Size1=10|FontName1=Times New Roman|Size2=8|FontName2=Arial|Size3=10|FontName3=Arial|Size4=12|Underline4=T|FontName4=Arial|Size5=11|FontName5=Arial|Size6=12|FontName6=Arial|Size7=14|FontName7=Arial|UseMBCS=T|IsBOC=T|HotSpotGridOn=T|HotSpotGridSize=2|SheetStyle=12|SystemFont=3|BorderOn=T|SheetNumberSpaceSize=12|AreaColor=16317695|SnapGridOn=T|SnapGridSize=5|VisibleGridOn=T|VisibleGridSize=10|CustomX=2338|CustomX_Frac=58268|CustomY=1653|CustomY_Frac=54331|CustomXZones=8|CustomYZones=6|CustomMarginWidth=19|CustomMarginWidth_Frac=80000|ShowTemplateGraphics=T|TemplateFileName=C:\Users\<user>\Documents\Altium\AD20\Templates\Timecard.SchDot|Display_Unit=0
|RECORD=39|IsNotAccesible=T|OwnerPartId=-1|FileName=C:\Users\<user>\Documents\Altium\AD20\Templates\Timecard.SchDot
|RECORD=4|OwnerIndex=1|OwnerPartId=-1|Location.X=1594|Location.Y=39|Color=8388608|FontID=4|Text=timingcard.com|URL=http://timingcard.com
|RECORD=6|OwnerIndex=1|IndexInSheet=1|OwnerPartId=-1|LocationCount=2|X1=1680|Y1=35|X2=1576|Y2=35
|RECORD=4|OwnerIndex=1|IndexInSheet=2|OwnerPartId=-1|Location.X=1615|Location.Y=27|Justification=4|Color=16711680|FontID=5|Text==SheetNumber
|RECORD=4|OwnerIndex=1|IndexInSheet=3|OwnerPartId=-1|Location.X=1581|Location.X_Frac=42446|Location.Y=29|Location.Y_Frac=96838|Justification=3|FontID=2|Text=SHEET
|RECORD=4|OwnerIndex=1|IndexInSheet=4|OwnerPartId=-1|Location.X=1639|Location.X_Frac=42446|Location.Y=29|Location.Y_Frac=96838|Justification=3|FontID=2|Text=OF
|RECORD=6|OwnerIndex=1|IndexInSheet=5|OwnerPartId=-1|LineWidth=1|LocationCount=2|X1=1679|X1_Frac=42446|Y1=117|Y1_Frac=96838|X2=1576|Y2=118
|RECORD=4|OwnerIndex=1|IndexInSheet=6|OwnerPartId=-1|Location.X=1659|Location.Y=27|Justification=4|Color=16711680|FontID=5|Text==SheetTotal
|RECORD=30|OwnerIndex=1|IndexInSheet=7|OwnerPartId=-1|Location.X=1578|Location.Y=65|Corner.X=1673|Corner.X_Frac=88801|Corner.Y=115|KeepAspect=T|FileName=C:\Users\<user>\Desktop\Timecard Logo\TIMECARD.jpg
|RECORD=6|OwnerIndex=1|IndexInSheet=8|OwnerPartId=-1|LineWidth=1|LocationCount=2|X1=1576|X1_Frac=3162|Y1=117|Y1_Frac=42446|X2=1576|Y2=21
|RECORD=6|OwnerIndex=1|IndexInSheet=9|OwnerPartId=-1|LocationCount=2|X1=1680|Y1=51|X2=1576|Y2=51
|RECORD=4|OwnerIndex=1|IndexInSheet=10|OwnerPartId=-1|Location.X=1581|Location.X_Frac=42446|Location.Y=56|Location.Y_Frac=96838|Justification=3|FontID=2|Text=REV
|RECORD=4|OwnerIndex=1|IndexInSheet=11|OwnerPartId=-1|Location.X=1619|Location.Y=57|Justification=3|FontID=2|Text=DATE
|RECORD=6|OwnerIndex=1|IndexInSheet=12|OwnerPartId=-1|LocationCount=2|X1=1680|Y1=65|X2=1576|Y2=65
|RECORD=4|OwnerIndex=1|IndexInSheet=13|OwnerPartId=-1|Location.X=1605|Location.Y=58|Justification=4|Color=16711680|FontID=5|Text==ProjectRevision
|RECORD=4|OwnerIndex=1|IndexInSheet=14|OwnerPartId=-1|Location.X=1659|Location.Y=58|Justification=4|Color=16711680|FontID=5|Text==ProjectDate
|RECORD=41|IndexInSheet=1|OwnerPartId=-1|Location.X=21474|Location.X_Frac=83647|Location.Y=21464|Location.Y_Frac=83647|Color=8388608|FontID=1|IsHidden=T|Text=01910|Name=Customer
|RECORD=41|IndexInSheet=2|OwnerPartId=-1|Location.X=1000|Location.Y=10|Color=8388608|FontID=1|IsHidden=T|Text=*|Name=DocStatus
|RECORD=17|IndexInSheet=3|OwnerPartId=-1|ShowNetName=T|Location.X=472|Location.Y=807|Orientation=1|Color=128|FontID=1|Text=+12V
|RECORD=17|IndexInSheet=4|OwnerPartId=-1|Style=4|ShowNetName=T|Location.X=472|Location.Y=697|Orientation=3|Color=128|FontID=1|Text=GND
|RECORD=17|IndexInSheet=5|OwnerPartId=-1|ShowNetName=T|Location.X=930|Location.Y=950|Orientation=1|Color=128|FontID=1|Text=+5.0V
|RECORD=17|IndexInSheet=6|OwnerPartId=-1|ShowNetName=T|Location.X=1330|Location.Y=440|Orientation=1|Color=128|FontID=1|Text=+3.3V
|RECORD=17|IndexInSheet=7|OwnerPartId=-1|Style=4|ShowNetName=T|Location.X=580|Location.Y=730|Orientation=3|Color=128|FontID=1|Text=GND
|RECORD=17|IndexInSheet=8|OwnerPartId=-1|Style=4|ShowNetName=T|Location.X=860|Location.Y=730|Orientation=3|Color=128|FontID=1|Text=GND
|RECORD=17|IndexInSheet=9|OwnerPartId=-1|Style=4|ShowNetName=T|Location.X=1330|Location.Y=280|Orientation=3|Color=128|FontID=1|Text=GND
|RECORD=17|IndexInSheet=10|OwnerPartId=-1|Style=4|ShowNetName=T|Location.X=530|Location.Y=280|Orientation=3|Color=128|FontID=1|Text=GND
|RECORD=17|IndexInSheet=11|OwnerPartId=-1|Style=4|ShowNetName=T|Location.X=810|Location.Y=280|Orientation=3|Color=128|FontID=1|Text=GND
|RECORD=17|IndexInSheet=12|OwnerPartId=-1|ShowNetName=T|Location.X=970|Location.Y=550|Orientation=1|Color=128|FontID=1|Text=+3.3V
|RECORD=17|IndexInSheet=13|OwnerPartId=-1|ShowNetName=T|Location.X=530|Location.Y=960|Orientation=1|Color=128|FontID=1|Text=+12V
|RECORD=17|IndexInSheet=14|OwnerPartId=-1|ShowNetName=T|Location.X=530|Location.Y=560|Orientation=1|Color=128|FontID=1|Text=+12V
|RECORD=1|LibReference=CAP_0805_10UF_25V|ComponentDescription=CAP, CER, 10.UF, 25V, 10%, X5R, 0805|PartCount=2|DisplayModeCount=1|IndexInSheet=15|OwnerPartId=-1|Location.X=402|Location.Y=697|CurrentPartId=1|LibraryPath=*|SourceLibraryName=Capacitors.IntLib|TargetFileName=*|AreaColor=11599871|Color=128|PartIDLocked=F|DesignItemId=CAP_0805_10UF_25V|AllPinCount=2
|RECORD=41|OwnerIndex=31|OwnerPartId=-1|Location.X=402|Location.Y=697|Color=8388608|FontID=6|IsHidden=T|Text=TAIYO YUDEN|Name=MFG NAME
|RECORD=41|OwnerIndex=31|IndexInSheet=1|OwnerPartId=-1|Location.X=402|Location.Y=697|Color=8388608|FontID=6|IsHidden=T|Text=TMK212BBJ106KG-T|Name=MFG PART NUM
|RECORD=41|OwnerIndex=31|IndexInSheet=2|OwnerPartId=-1|Location.X=402|Location.Y=697|Color=8388608|FontID=6|IsHidden=T|Text=10/23/2013|Name=MODIFY DATE
|RECORD=41|OwnerIndex=31|IndexInSheet=3|OwnerPartId=-1|Location.X=402|Location.Y=697|Color=8388608|FontID=6|IsHidden=T|Text=CAP, CER|Name=CATEGORY
|RECORD=41|OwnerIndex=31|IndexInSheet=4|OwnerPartId=-1|Location.X=400|Location.Y=709|Location.Y_Frac=50000|Color=8388608|FontID=6|IsHidden=T|Text=4/11/2006 3:37:28 PM|Name=Date
|RECORD=41|OwnerIndex=31|IndexInSheet=5|OwnerPartId=-1|Location.X=408|Location.Y=771|Location.Y_Frac=48252|Color=8388608|FontID=6|IsHidden=T|Text=*|Name=SHEETPART
|RECORD=41|OwnerIndex=31|IndexInSheet=6|OwnerPartId=-1|Location.X=408|Location.Y=771|Location.Y_Frac=48252|Color=8388608|FontID=6|IsHidden=T|Text=10%|Name=P1
|RECORD=41|OwnerIndex=31|IndexInSheet=7|OwnerPartId=-1|Location.X=408|Location.Y=771|Location.Y_Frac=48252|Color=8388608|FontID=6|IsHidden=T|Text=85C|Name=MAXTEMP
|RECORD=41|OwnerIndex=31|IndexInSheet=8|OwnerPartId=-1|Location.X=408|Location.Y=771|Location.Y_Frac=48252|Color=8388608|FontID=6|IsHidden=T|Text=-55C|Name=MINTEMP
|RECORD=41|OwnerIndex=31|IndexInSheet=9|OwnerPartId=-1|Location.X=408|Location.Y=771|Location.Y_Frac=48252|Color=8388608|FontID=6|IsHidden=T|Name=OTHER
|RECORD=41|OwnerIndex=31|IndexInSheet=10|OwnerPartId=-1|Location.X=408|Location.Y=771|Location.Y_Frac=48252|Color=8388608|FontID=6|IsHidden=T|Text=25V|Name=P2
|RECORD=41|OwnerIndex=31|IndexInSheet=11|OwnerPartId=-1|Location.X=408|Location.Y=771|Location.Y_Frac=48252|Color=8388608|FontID=6|IsHidden=T|Text=X5R|Name=P3
|RECORD=41|OwnerIndex=31|IndexInSheet=12|OwnerPartId=-1|Location.X=408|Location.Y=771|Location.Y_Frac=48252|Color=8388608|FontID=6|IsHidden=T|Text=0805|Name=Size
|RECORD=41|OwnerIndex=31|IndexInSheet=13|OwnerPartId=-1|Location.X=408|Location.Y=771|Location.Y_Frac=48252|Color=8388608|FontID=6|IsHidden=T|Name=SUB
|RECORD=41|OwnerIndex=31|IndexInSheet=14|OwnerPartId=-1|Location.X=408|Location.Y=771|Location.Y_Frac=48252|Color=8388608|FontID=1|IsHidden=T|Text=CAP, CER, 10.UF, 10V, 10%, X5R, 0805|Name=DESC
|RECORD=41|OwnerIndex=31|IndexInSheet=15|OwnerPartId=-1|Location.X=408|Location.Y=770|Location.Y_Frac=98252|Color=8388608|FontID=1|IsHidden=T|Text=MOUSER|Name=Supplier 1|ReadOnlyState=1
|RECORD=41|OwnerIndex=31|IndexInSheet=16|OwnerPartId=-1|Location.X=408|Location.Y=770|Location.Y_Frac=98252|Color=8388608|FontID=1|IsHidden=T|Text=963-TMK212BBJ106KG-T|Name=Supplier Part Number 1|ReadOnlyState=1
|RECORD=41|OwnerIndex=31|IndexInSheet=17|OwnerPartId=-1|Location.X=432|Location.Y=727|Color=8388608|FontID=6|Text=10uF|Name=VALUE
|RECORD=2|OwnerIndex=31|OwnerPartId=1|FormalType=1|Electrical=4|PinConglomerate=35|PinLength=10|Location.X=422|Location.Y=727|Name=2|Designator=2|SwapIdPin=2|SwapIDPart=1|PinPropagationDelay=0.000000E+000
|RECORD=2|OwnerIndex=31|OwnerPartId=1|FormalType=1|Electrical=4|PinConglomerate=33|PinLength=10|Location.X=422|Location.Y=737|Name=1|Designator=1|SwapIdPin=1|SwapIDPart=1|PinPropagationDelay=0.000000E+000
|RECORD=13|OwnerIndex=31|IsNotAccesible=T|IndexInSheet=20|OwnerPartId=1|Location.X=422|Location.Y=729|Location.Y_Frac=50000|Corner.X=422|Corner.Y=727|LineWidth=1|Color=16711680
|RECORD=13|OwnerIndex=31|IsNotAccesible=T|IndexInSheet=21|OwnerPartId=1|Location.X=422|Location.Y=737|Corner.X=422|Corner.Y=734|Corner.Y_Frac=50000|LineWidth=1|Color=16711680
|RECORD=13|OwnerIndex=31|IsNotAccesible=T|IndexInSheet=22|OwnerPartId=1|Location.X=427|Location.Y=729|Location.Y_Frac=50000|Corner.X=417|Corner.Y=729|Corner.Y_Frac=50000|LineWidth=1|Color=16711680
|RECORD=13|OwnerIndex=31|IsNotAccesible=T|IndexInSheet=23|OwnerPartId=1|Location.X=427|Location.Y=734|Location.Y_Frac=50000|Corner.X=417|Corner.Y=734|Corner.Y_Frac=50000|LineWidth=1|Color=16711680
|RECORD=41|OwnerIndex=31|IndexInSheet=24|OwnerPartId=-1|Location.X=408|Location.Y=770|Location.Y_Frac=98951|Color=8388608|FontID=1|IsHidden=T|Text=<VALENTIUM>|Name=VALENTIUM PART NUM
|RECORD=34|OwnerIndex=31|IndexInSheet=-1|OwnerPartId=-1|Location.X=432|Location.Y=737|Color=8388608|FontID=1|Text=C1|Name=Designator|ReadOnlyState=1
|RECORD=41|OwnerIndex=31|IndexInSheet=-1|OwnerPartId=-1|Location.X=429|Location.X_Frac=50000|Location.Y=692|Color=8388608|FontID=1|IsHidden=T|Text=CAP_0805_10UF_25V|Name=Comment
|RECORD=44|OwnerIndex=31
|RECORD=45|OwnerIndex=61|IndexInSheet=-1|Description=Chip Capacitor, 0805, 2-Leads, Body 2.00x1.25mm, IPC Medium Density|UseComponentLibrary=T|ModelName=CAPC2012X14N|ModelType=PCBLIB|DatafileCount=1|ModelDatafileEntity0=CAPC2012X14N|ModelDatafileKind0=PCBLib|IsCurrent=T|DatalinksLocked=T|DatabaseDatalinksLocked=T|IntegratedModel=T|DatabaseModel=T
|RECORD=46|OwnerIndex=62
|RECORD=48|OwnerIndex=62
|RECORD=1|LibReference=CAP_0805_10UF_25V|ComponentDescription=CAP, CER, 10.UF, 25V, 10%, X5R, 0805|PartCount=2|DisplayModeCount=1|IndexInSheet=16|OwnerPartId=-1|Location.X=510|Location.Y=890|CurrentPartId=1|LibraryPath=*|SourceLibraryName=Capacitors.IntLib|TargetFileName=*|AreaColor=11599871|Color=128|PartIDLocked=F|DesignItemId=CAP_0805_10UF_25V|AllPinCount=2
|RECORD=41|OwnerIndex=65|OwnerPartId=-1|Location.X=510|Location.Y=890|Color=8388608|FontID=6|IsHidden=T|Text=TAIYO YUDEN|Name=MFG NAME
|RECORD=41|OwnerIndex=65|IndexInSheet=1|OwnerPartId=-1|Location.X=510|Location.Y=890|Color=8388608|FontID=6|IsHidden=T|Text=TMK212BBJ106KG-T|Name=MFG PART NUM
|RECORD=41|OwnerIndex=65|IndexInSheet=2|OwnerPartId=-1|Location.X=510|Location.Y=890|Color=8388608|FontID=6|IsHidden=T|Text=10/23/2013|Name=MODIFY DATE
|RECORD=41|OwnerIndex=65|IndexInSheet=3|OwnerPartId=-1|Location.X=510|Location.Y=890|Color=8388608|FontID=6|IsHidden=T|Text=CAP, CER|Name=CATEGORY
|RECORD=41|OwnerIndex=65|IndexInSheet=4|OwnerPartId=-1|Location.X=508|Location.Y=902|Location.Y_Frac=50000|Color=8388608|FontID=6|IsHidden=T|Text=4/11/2006 3:37:28 PM|Name=Date
|RECORD=41|OwnerIndex=65|IndexInSheet=5|OwnerPartId=-1|Location.X=516|Location.Y=964|Location.Y_Frac=48252|Color=8388608|FontID=6|IsHidden=T|Text=*|Name=SHEETPART
|RECORD=41|OwnerIndex=65|IndexInSheet=6|OwnerPartId=-1|Location.X=516|Location.Y=964|Location.Y_Frac=48252|Color=8388608|FontID=6|IsHidden=T|Text=10%|Name=P1
|RECORD=41|OwnerIndex=65|IndexInSheet=7|OwnerPartId=-1|Location.X=516|Location.Y=964|Location.Y_Frac=48252|Color=8388608|FontID=6|IsHidden=T|Text=85C|Name=MAXTEMP
|RECORD=41|OwnerIndex=65|IndexInSheet=8|OwnerPartId=-1|Location.X=516|Location.Y=964|Location.Y_Frac=48252|Color=8388608|FontID=6|IsHidden=T|Text=-55C|Name=MINTEMP
|RECORD=41|OwnerIndex=65|IndexInSheet=9|OwnerPartId=-1|Location.X=516|Location.Y=964|Location.Y_Frac=48252|Color=8388608|FontID=6|IsHidden=T|Name=OTHER
|RECORD=41|OwnerIndex=65|IndexInSheet=10|OwnerPartId=-1|Location.X=516|Location.Y=964|Location.Y_Frac=48252|Color=8388608|FontID=6|IsHidden=T|Text=25V|Name=P2
|RECORD=41|OwnerIndex=65|IndexInSheet=11|OwnerPartId=-1|Location.X=516|Location.Y=964|Location.Y_Frac=48252|Color=8388608|FontID=6|IsHidden=T|Text=X5R|Name=P3
|RECORD=41|OwnerIndex=65|IndexInSheet=12|OwnerPartId=-1|Location.X=516|Location.Y=964|Location.Y_Frac=48252|Color=8388608|FontID=6|IsHidden=T|Text=0805|Name=Size
|RECORD=41|OwnerIndex=65|IndexInSheet=13|OwnerPartId=-1|Location.X=516|Location.Y=964|Location.Y_Frac=48252|Color=8388608|FontID=6|IsHidden=T|Name=SUB
|RECORD=41|OwnerIndex=65|IndexInSheet=14|OwnerPartId=-1|Location.X=516|Location.Y=964|Location.Y_Frac=48252|Color=8388608|FontID=1|IsHidden=T|Text=CAP, CER, 10.UF, 10V, 10%, X5R, 0805|Name=DESC
|RECORD=41|OwnerIndex=65|IndexInSheet=15|OwnerPartId=-1|Location.X=516|Location.Y=963|Location.Y_Frac=98252|Color=8388608|FontID=1|IsHidden=T|Text=MOUSER|Name=Supplier 1|ReadOnlyState=1
|RECORD=41|OwnerIndex=65|IndexInSheet=16|OwnerPartId=-1|Location.X=516|Location.Y=963|Location.Y_Frac=98252|Color=8388608|FontID=1|IsHidden=T|Text=963-TMK212BBJ106KG-T|Name=Supplier Part Number 1|ReadOnlyState=1
|RECORD=41|OwnerIndex=65|IndexInSheet=17|OwnerPartId=-1|Location.X=540|Location.Y=920|Color=8388608|FontID=6|Text=10uF|Name=VALUE
|RECORD=2|OwnerIndex=65|OwnerPartId=1|FormalType=1|Electrical=4|PinConglomerate=35|PinLength=10|Location.X=530|Location.Y=920|Name=2|Designator=2|SwapIdPin=2|SwapIDPart=1|PinPropagationDelay=0.000000E+000
|RECORD=2|OwnerIndex=65|OwnerPartId=1|FormalType=1|Electrical=4|PinConglomerate=33|PinLength=10|Location.X=530|Location.Y=930|Name=1|Designator=1|SwapIdPin=1|SwapIDPart=1|PinPropagationDelay=0.000000E+000
|RECORD=13|OwnerIndex=65|IsNotAccesible=T|IndexInSheet=20|OwnerPartId=1|Location.X=530|Location.Y=922|Location.Y_Frac=50000|Corner.X=530|Corner.Y=920|LineWidth=1|Color=16711680
|RECORD=13|OwnerIndex=65|IsNotAccesible=T|IndexInSheet=21|OwnerPartId=1|Location.X=530|Location.Y=930|Corner.X=530|Corner.Y=927|Corner.Y_Frac=50000|LineWidth=1|Color=16711680
|RECORD=13|OwnerIndex=65|IsNotAccesible=T|IndexInSheet=22|OwnerPartId=1|Location.X=535|Location.Y=922|Location.Y_Frac=50000|Corner.X=525|Corner.Y=922|Corner.Y_Frac=50000|LineWidth=1|Color=16711680
|RECORD=13|OwnerIndex=65|IsNotAccesible=T|IndexInSheet=23|OwnerPartId=1|Location.X=535|Location.Y=927|Location.Y_Frac=50000|Corner.X=525|Corner.Y=927|Corner.Y_Frac=50000|LineWidth=1|Color=16711680
|RECORD=41|OwnerIndex=65|IndexInSheet=24|OwnerPartId=-1|Location.X=516|Location.Y=963|Location.Y_Frac=98951|Color=8388608|FontID=1|IsHidden=T|Text=<VALENTIUM>|Name=VALENTIUM PART NUM
|RECORD=34|OwnerIndex=65|IndexInSheet=-1|OwnerPartId=-1|Location.X=540|Location.Y=930|Color=8388608|FontID=1|Text=C6|Name=Designator|ReadOnlyState=1
|RECORD=41|OwnerIndex=65|IndexInSheet=-1|OwnerPartId=-1|Location.X=537|Location.X_Frac=50000|Location.Y=885|Color=8388608|FontID=1|IsHidden=T|Text=CAP_0805_10UF_25V|Name=Comment
|RECORD=44|OwnerIndex=65
|RECORD=45|OwnerIndex=95|IndexInSheet=-1|Description=Chip Capacitor, 0805, 2-Leads, Body 2.00x1.25mm, IPC Medium Density|UseComponentLibrary=T|ModelName=CAPC2012X14N|ModelType=PCBLIB|DatafileCount=1|ModelDatafileEntity0=CAPC2012X14N|ModelDatafileKind0=PCBLib|IsCurrent=T|DatalinksLocked=T|DatabaseDatalinksLocked=T|IntegratedModel=T|DatabaseModel=T
|RECORD=46|OwnerIndex=96
|RECORD=48|OwnerIndex=96
|RECORD=1|LibReference=CAP_0805_10UF_25V|ComponentDescription=CAP, CER, 10.UF, 25V, 10%, X5R, 0805|PartCount=2|DisplayModeCount=1|IndexInSheet=17|OwnerPartId=-1|Location.X=1010|Location.Y=760|CurrentPartId=1|LibraryPath=*|SourceLibraryName=Capacitors.IntLib|TargetFileName=*|AreaColor=11599871|Color=128|PartIDLocked=F|DesignItemId=CAP_0805_10UF_25V|AllPinCount=2
|RECORD=41|OwnerIndex=99|OwnerPartId=-1|Location.X=1010|Location.Y=760|Color=8388608|FontID=6|IsHidden=T|Text=TAIYO YUDEN|Name=MFG NAME
|RECORD=41|OwnerIndex=99|IndexInSheet=1|OwnerPartId=-1|Location.X=1010|Location.Y=760|Color=8388608|FontID=6|IsHidden=T|Text=TMK212BBJ106KG-T|Name=MFG PART NUM
|RECORD=41|OwnerIndex=99|IndexInSheet=2|OwnerPartId=-1|Location.X=1010|Location.Y=760|Color=8388608|FontID=6|IsHidden=T|Text=10/23/2013|Name=MODIFY DATE
|RECORD=41|OwnerIndex=99|IndexInSheet=3|OwnerPartId=-1|Location.X=1010|Location.Y=760|Color=8388608|FontID=6|IsHidden=T|Text=CAP, CER|Name=CATEGORY
|RECORD=41|OwnerIndex=99|IndexInSheet=4|OwnerPartId=-1|Location.X=1008|Location.Y=772|Location.Y_Frac=50000|Color=8388608|FontID=6|IsHidden=T|Text=4/11/2006 3:37:28 PM|Name=Date
|RECORD=41|OwnerIndex=99|IndexInSheet=5|OwnerPartId=-1|Location.X=1016|Location.Y=834|Location.Y_Frac=48252|Color=8388608|FontID=6|IsHidden=T|Text=*|Name=SHEETPART
|RECORD=41|OwnerIndex=99|IndexInSheet=6|OwnerPartId=-1|Location.X=1016|Location.Y=834|Location.Y_Frac=48252|Color=8388608|FontID=6|IsHidden=T|Text=10%|Name=P1
|RECORD=41|OwnerIndex=99|IndexInSheet=7|OwnerPartId=-1|Location.X=1016|Location.Y=834|Location.Y_Frac=48252|Color=8388608|FontID=6|IsHidden=T|Text=85C|Name=MAXTEMP
|RECORD=41|OwnerIndex=99|IndexInSheet=8|OwnerPartId=-1|Location.X=1016|Location.Y=834|Location.Y_Frac=48252|Color=8388608|FontID=6|IsHidden=T|Text=-55C|Name=MINTEMP
|RECORD=41|OwnerIndex=99|IndexInSheet=9|OwnerPartId=-1|Location.X=1016|Location.Y=834|Location.Y_Frac=48252|Color=8388608|FontID=6|IsHidden=T|Name=OTHER
|RECORD=41|OwnerIndex=99|IndexInSheet=10|OwnerPartId=-1|Location.X=1016|Location.Y=834|Location.Y_Frac=48252|Color=8388608|FontID=6|IsHidden=T|Text=25V|Name=P2
|RECORD=41|OwnerIndex=99|IndexInSheet=11|OwnerPartId=-1|Location.X=1016|Location.Y=834|Location.Y_Frac=48252|Color=8388608|FontID=6|IsHidden=T|Text=X5R|Name=P3
|RECORD=41|OwnerIndex=99|IndexInSheet=12|OwnerPartId=-1|Location.X=1016|Location.Y=834|Location.Y_Frac=48252|Color=8388608|FontID=6|IsHidden=T|Text=0805|Name=Size
|RECORD=41|OwnerIndex=99|IndexInSheet=13|OwnerPartId=-1|Location.X=1016|Location.Y=834|Location.Y_Frac=48252|Color=8388608|FontID=6|IsHidden=T|Name=SUB
|RECORD=41|OwnerIndex=99|IndexInSheet=14|OwnerPartId=-1|Location.X=1016|Location.Y=834|Location.Y_Frac=48252|Color=8388608|FontID=1|IsHidden=T|Text=CAP, CER, 10.UF, 10V, 10%, X5R, 0805|Name=DESC
|RECORD=41|OwnerIndex=99|IndexInSheet=15|OwnerPartId=-1|Location.X=1016|Location.Y=833|Location.Y_Frac=98252|Color=8388608|FontID=1|IsHidden=T|Text=MOUSER|Name=Supplier 1|ReadOnlyState=1
|RECORD=41|OwnerIndex=99|IndexInSheet=16|OwnerPartId=-1|Location.X=1016|Location.Y=833|Location.Y_Frac=98252|Color=8388608|FontID=1|IsHidden=T|Text=963-TMK212BBJ106KG-T|Name=Supplier Part Number 1|ReadOnlyState=1
|RECORD=41|OwnerIndex=99|IndexInSheet=17|OwnerPartId=-1|Location.X=1040|Location.Y=790|Color=8388608|FontID=6|Text=10uF|Name=VALUE
|RECORD=2|OwnerIndex=99|OwnerPartId=1|FormalType=1|Electrical=4|PinConglomerate=35|PinLength=10|Location.X=1030|Location.Y=790|Name=2|Designator=2|SwapIdPin=2|SwapIDPart=1|PinPropagationDelay=0.000000E+000
|RECORD=2|OwnerIndex=99|OwnerPartId=1|FormalType=1|Electrical=4|PinConglomerate=33|PinLength=10|Location.X=1030|Location.Y=800|Name=1|Designator=1|SwapIdPin=1|SwapIDPart=1|PinPropagationDelay=0.000000E+000
|RECORD=13|OwnerIndex=99|IsNotAccesible=T|IndexInSheet=20|OwnerPartId=1|Location.X=1030|Location.Y=792|Location.Y_Frac=50000|Corner.X=1030|Corner.Y=790|LineWidth=1|Color=16711680
|RECORD=13|OwnerIndex=99|IsNotAccesible=T|IndexInSheet=21|OwnerPartId=1|Location.X=1030|Location.Y=800|Corner.X=1030|Corner.Y=797|Corner.Y_Frac=50000|LineWidth=1|Color=16711680
|RECORD=13|OwnerIndex=99|IsNotAccesible=T|IndexInSheet=22|OwnerPartId=1|Location.X=1035|Location.Y=792|Location.Y_Frac=50000|Corner.X=1025|Corner.Y=792|Corner.Y_Frac=50000|LineWidth=1|Color=16711680
|RECORD=13|OwnerIndex=99|IsNotAccesible=T|IndexInSheet=23|OwnerPartId=1|Location.X=1035|Location.Y=797|Location.Y_Frac=50000|Corner.X=1025|Corner.Y=797|Corner.Y_Frac=50000|LineWidth=1|Color=16711680
|RECORD=41|OwnerIndex=99|IndexInSheet=24|OwnerPartId=-1|Location.X=1016|Location.Y=833|Location.Y_Frac=98951|Color=8388608|FontID=1|IsHidden=T|Text=<VALENTIUM>|Name=VALENTIUM PART NUM
|RECORD=34|OwnerIndex=99|IndexInSheet=-1|OwnerPartId=-1|Location.X=1040|Location.Y=800|Color=8388608|FontID=1|Text=C14|Name=Designator|ReadOnlyState=1
|RECORD=41|OwnerIndex=99|IndexInSheet=-1|OwnerPartId=-1|Location.X=1037|Location.X_Frac=50000|Location.Y=755|Color=8388608|FontID=1|IsHidden=T|Text=CAP_0805_10UF_25V|Name=Comment
|RECORD=44|OwnerIndex=99
|RECORD=45|OwnerIndex=129|IndexInSheet=-1|Description=Chip Capacitor, 0805, 2-Leads, Body 2.00x1.25mm, IPC Medium Density|UseComponentLibrary=T|ModelName=CAPC2012X14N|ModelType=PCBLIB|DatafileCount=1|ModelDatafileEntity0=CAPC2012X14N|ModelDatafileKind0=PCBLib|IsCurrent=T|DatalinksLocked=T|DatabaseDatalinksLocked=T|IntegratedModel=T|DatabaseModel=T
|RECORD=46|OwnerIndex=130
|RECORD=48|OwnerIndex=130
|RECORD=1|LibReference=CAP_0805_10UF_25V|ComponentDescription=CAP, CER, 10.UF, 25V, 10%, X5R, 0805|PartCount=2|DisplayModeCount=1|IndexInSheet=18|OwnerPartId=-1|Location.X=960|Location.Y=760|CurrentPartId=1|LibraryPath=*|SourceLibraryName=Capacitors.IntLib|TargetFileName=*|AreaColor=11599871|Color=128|PartIDLocked=F|DesignItemId=CAP_0805_10UF_25V|AllPinCount=2
|RECORD=41|OwnerIndex=133|OwnerPartId=-1|Location.X=960|Location.Y=760|Color=8388608|FontID=6|IsHidden=T|Text=TAIYO YUDEN|Name=MFG NAME
|RECORD=41|OwnerIndex=133|IndexInSheet=1|OwnerPartId=-1|Location.X=960|Location.Y=760|Color=8388608|FontID=6|IsHidden=T|Text=TMK212BBJ106KG-T|Name=MFG PART NUM
|RECORD=41|OwnerIndex=133|IndexInSheet=2|OwnerPartId=-1|Location.X=960|Location.Y=760|Color=8388608|FontID=6|IsHidden=T|Text=10/23/2013|Name=MODIFY DATE
|RECORD=41|OwnerIndex=133|IndexInSheet=3|OwnerPartId=-1|Location.X=960|Location.Y=760|Color=8388608|FontID=6|IsHidden=T|Text=CAP, CER|Name=CATEGORY
|RECORD=41|OwnerIndex=133|IndexInSheet=4|OwnerPartId=-1|Location.X=958|Location.Y=772|Location.Y_Frac=50000|Color=8388608|FontID=6|IsHidden=T|Text=4/11/2006 3:37:28 PM|Name=Date
|RECORD=41|OwnerIndex=133|IndexInSheet=5|OwnerPartId=-1|Location.X=966|Location.Y=834|Location.Y_Frac=48252|Color=8388608|FontID=6|IsHidden=T|Text=*|Name=SHEETPART
|RECORD=41|OwnerIndex=133|IndexInSheet=6|OwnerPartId=-1|Location.X=966|Location.Y=834|Location.Y_Frac=48252|Color=8388608|FontID=6|IsHidden=T|Text=10%|Name=P1
|RECORD=41|OwnerIndex=133|IndexInSheet=7|OwnerPartId=-1|Location.X=966|Location.Y=834|Location.Y_Frac=48252|Color=8388608|FontID=6|IsHidden=T|Text=85C|Name=MAXTEMP
|RECORD=41|OwnerIndex=133|IndexInSheet=8|OwnerPartId=-1|Location.X=966|Location.Y=834|Location.Y_Frac=48252|Color=8388608|FontID=6|IsHidden=T|Text=-55C|Name=MINTEMP
|RECORD=41|OwnerIndex=133|IndexInSheet=9|OwnerPartId=-1|Location.X=966|Location.Y=834|Location.Y_Frac=48252|Color=8388608|FontID=6|IsHidden=T|Name=OTHER
|RECORD=41|OwnerIndex=133|IndexInSheet=10|OwnerPartId=-1|Location.X=966|Location.Y=834|Location.Y_Frac=48252|Color=8388608|FontID=6|IsHidden=T|Text=25V|Name=P2
|RECORD=41|OwnerIndex=133|IndexInSheet=11|OwnerPartId=-1|Location.X=966|Location.Y=834|Location.Y_Frac=48252|Color=8388608|FontID=6|IsHidden=T|Text=X5R|Name=P3
|RECORD=41|OwnerIndex=133|IndexInSheet=12|OwnerPartId=-1|Location.X=966|Location.Y=834|Location.Y_Frac=48252|Color=8388608|FontID=6|IsHidden=T|Text=0805|Name=Size
|RECORD=41|OwnerIndex=133|IndexInSheet=13|OwnerPartId=-1|Location.X=966|Location.Y=834|Location.Y_Frac=48252|Color=8388608|FontID=6|IsHidden=T|Name=SUB
|RECORD=41|OwnerIndex=133|IndexInSheet=14|OwnerPartId=-1|Location.X=966|Location.Y=834|Location.Y_Frac=48252|Color=8388608|FontID=1|IsHidden=T|Text=CAP, CER, 10.UF, 10V, 10%, X5R, 0805|Name=DESC
|RECORD=41|OwnerIndex=133|IndexInSheet=15|OwnerPartId=-1|Location.X=966|Location.Y=833|Location.Y_Frac=98252|Color=8388608|FontID=1|IsHidden=T|Text=MOUSER|Name=Supplier 1|ReadOnlyState=1
|RECORD=41|OwnerIndex=133|IndexInSheet=16|OwnerPartId=-1|Location.X=966|Location.Y=833|Location.Y_Frac=98252|Color=8388608|FontID=1|IsHidden=T|Text=963-TMK212BBJ106KG-T|Name=Supplier Part Number 1|ReadOnlyState=1
|RECORD=41|OwnerIndex=133|IndexInSheet=17|OwnerPartId=-1|Location.X=990|Location.Y=790|Color=8388608|FontID=6|Text=10uF|Name=VALUE
|RECORD=2|OwnerIndex=133|OwnerPartId=1|FormalType=1|Electrical=4|PinConglomerate=35|PinLength=10|Location.X=980|Location.Y=790|Name=2|Designator=2|SwapIdPin=2|SwapIDPart=1|PinPropagationDelay=0.000000E+000
|RECORD=2|OwnerIndex=133|OwnerPartId=1|FormalType=1|Electrical=4|PinConglomerate=33|PinLength=10|Location.X=980|Location.Y=800|Name=1|Designator=1|SwapIdPin=1|SwapIDPart=1|PinPropagationDelay=0.000000E+000
|RECORD=13|OwnerIndex=133|IsNotAccesible=T|IndexInSheet=20|OwnerPartId=1|Location.X=980|Location.Y=792|Location.Y_Frac=50000|Corner.X=980|Corner.Y=790|LineWidth=1|Color=16711680
|RECORD=13|OwnerIndex=133|IsNotAccesible=T|IndexInSheet=21|OwnerPartId=1|Location.X=980|Location.Y=800|Corner.X=980|Corner.Y=797|Corner.Y_Frac=50000|LineWidth=1|Color=16711680
|RECORD=13|OwnerIndex=133|IsNotAccesible=T|IndexInSheet=22|OwnerPartId=1|Location.X=985|Location.Y=792|Location.Y_Frac=50000|Corner.X=975|Corner.Y=792|Corner.Y_Frac=50000|LineWidth=1|Color=16711680
|RECORD=13|OwnerIndex=133|IsNotAccesible=T|IndexInSheet=23|OwnerPartId=1|Location.X=985|Location.Y=797|Location.Y_Frac=50000|Corner.X=975|Corner.Y=797|Corner.Y_Frac=50000|LineWidth=1|Color=16711680
|RECORD=41|OwnerIndex=133|IndexInSheet=24|OwnerPartId=-1|Location.X=966|Location.Y=833|Location.Y_Frac=98951|Color=8388608|FontID=1|IsHidden=T|Text=<VALENTIUM>|Name=VALENTIUM PART NUM
|RECORD=34|OwnerIndex=133|IndexInSheet=-1|OwnerPartId=-1|Location.X=990|Location.Y=800|Color=8388608|FontID=1|Text=C13|Name=Designator|ReadOnlyState=1
|RECORD=41|OwnerIndex=133|IndexInSheet=-1|OwnerPartId=-1|Location.X=987|Location.X_Frac=50000|Location.Y=755|Color=8388608|FontID=1|IsHidden=T|Text=CAP_0805_10UF_25V|Name=Comment
|RECORD=44|OwnerIndex=133
|RECORD=45|OwnerIndex=163|IndexInSheet=-1|Description=Chip Capacitor, 0805, 2-Leads, Body 2.00x1.25mm, IPC Medium Density|UseComponentLibrary=T|ModelName=CAPC2012X14N|ModelType=PCBLIB|DatafileCount=1|ModelDatafileEntity0=CAPC2012X14N|ModelDatafileKind0=PCBLib|IsCurrent=T|DatalinksLocked=T|DatabaseDatalinksLocked=T|IntegratedModel=T|DatabaseModel=T
|RECORD=46|OwnerIndex=164
|RECORD=48|OwnerIndex=164
|RECORD=1|LibReference=CAP_0805_10UF_25V|ComponentDescription=CAP, CER, 10.UF, 25V, 10%, X5R, 0805|PartCount=2|DisplayModeCount=1|IndexInSheet=19|OwnerPartId=-1|Location.X=510|Location.Y=490|CurrentPartId=1|LibraryPath=*|SourceLibraryName=Capacitors.IntLib|TargetFileName=*|AreaColor=11599871|Color=128|PartIDLocked=F|DesignItemId=CAP_0805_10UF_25V|AllPinCount=2
|RECORD=41|OwnerIndex=167|OwnerPartId=-1|Location.X=510|Location.Y=490|Color=8388608|FontID=6|IsHidden=T|Text=TAIYO YUDEN|Name=MFG NAME
|RECORD=41|OwnerIndex=167|IndexInSheet=1|OwnerPartId=-1|Location.X=510|Location.Y=490|Color=8388608|FontID=6|IsHidden=T|Text=TMK212BBJ106KG-T|Name=MFG PART NUM
|RECORD=41|OwnerIndex=167|IndexInSheet=2|OwnerPartId=-1|Location.X=510|Location.Y=490|Color=8388608|FontID=6|IsHidden=T|Text=10/23/2013|Name=MODIFY DATE
|RECORD=41|OwnerIndex=167|IndexInSheet=3|OwnerPartId=-1|Location.X=510|Location.Y=490|Color=8388608|FontID=6|IsHidden=T|Text=CAP, CER|Name=CATEGORY
|RECORD=41|OwnerIndex=167|IndexInSheet=4|OwnerPartId=-1|Location.X=508|Location.Y=502|Location.Y_Frac=50000|Color=8388608|FontID=6|IsHidden=T|Text=4/11/2006 3:37:28 PM|Name=Date
|RECORD=41|OwnerIndex=167|IndexInSheet=5|OwnerPartId=-1|Location.X=516|Location.Y=564|Location.Y_Frac=48252|Color=8388608|FontID=6|IsHidden=T|Text=*|Name=SHEETPART
|RECORD=41|OwnerIndex=167|IndexInSheet=6|OwnerPartId=-1|Location.X=516|Location.Y=564|Location.Y_Frac=48252|Color=8388608|FontID=6|IsHidden=T|Text=10%|Name=P1
|RECORD=41|OwnerIndex=167|IndexInSheet=7|OwnerPartId=-1|Location.X=516|Location.Y=564|Location.Y_Frac=48252|Color=8388608|FontID=6|IsHidden=T|Text=85C|Name=MAXTEMP
|RECORD=41|OwnerIndex=167|IndexInSheet=8|OwnerPartId=-1|Location.X=516|Location.Y=564|Location.Y_Frac=48252|Color=8388608|FontID=6|IsHidden=T|Text=-55C|Name=MINTEMP
|RECORD=41|OwnerIndex=167|IndexInSheet=9|OwnerPartId=-1|Location.X=516|Location.Y=564|Location.Y_Frac=48252|Color=8388608|FontID=6|IsHidden=T|Name=OTHER
|RECORD=41|OwnerIndex=167|IndexInSheet=10|OwnerPartId=-1|Location.X=516|Location.Y=564|Location.Y_Frac=48252|Color=8388608|FontID=6|IsHidden=T|Text=25V|Name=P2
|RECORD=41|OwnerIndex=167|IndexInSheet=11|OwnerPartId=-1|Location.X=516|Location.Y=564|Location.Y_Frac=48252|Color=8388608|FontID=6|IsHidden=T|Text=X5R|Name=P3
|RECORD=41|OwnerIndex=167|IndexInSheet=12|OwnerPartId=-1|Location.X=516|Location.Y=564|Location.Y_Frac=48252|Color=8388608|FontID=6|IsHidden=T|Text=0805|Name=Size
|RECORD=41|OwnerIndex=167|IndexInSheet=13|OwnerPartId=-1|Location.X=516|Location.Y=564|Location.Y_Frac=48252|Color=8388608|FontID=6|IsHidden=T|Name=SUB
|RECORD=41|OwnerIndex=167|IndexInSheet=14|OwnerPartId=-1|Location.X=516|Location.Y=564|Location.Y_Frac=48252|Color=8388608|FontID=1|IsHidden=T|Text=CAP, CER, 10.UF, 10V, 10%, X5R, 0805|Name=DESC
|RECORD=41|OwnerIndex=167|IndexInSheet=15|OwnerPartId=-1|Location.X=516|Location.Y=563|Location.Y_Frac=98252|Color=8388608|FontID=1|IsHidden=T|Text=MOUSER|Name=Supplier 1|ReadOnlyState=1
|RECORD=41|OwnerIndex=167|IndexInSheet=16|OwnerPartId=-1|Location.X=516|Location.Y=563|Location.Y_Frac=98252|Color=8388608|FontID=1|IsHidden=T|Text=963-TMK212BBJ106KG-T|Name=Supplier Part Number 1|ReadOnlyState=1
|RECORD=41|OwnerIndex=167|IndexInSheet=17|OwnerPartId=-1|Location.X=540|Location.Y=520|Color=8388608|FontID=6|Text=10uF|Name=VALUE
|RECORD=2|OwnerIndex=167|OwnerPartId=1|FormalType=1|Electrical=4|PinConglomerate=35|PinLength=10|Location.X=530|Location.Y=520|Name=2|Designator=2|SwapIdPin=2|SwapIDPart=1|PinPropagationDelay=0.000000E+000
|RECORD=2|OwnerIndex=167|OwnerPartId=1|FormalType=1|Electrical=4|PinConglomerate=33|PinLength=10|Location.X=530|Location.Y=530|Name=1|Designator=1|SwapIdPin=1|SwapIDPart=1|PinPropagationDelay=0.000000E+000
|RECORD=13|OwnerIndex=167|IsNotAccesible=T|IndexInSheet=20|OwnerPartId=1|Location.X=530|Location.Y=522|Location.Y_Frac=50000|Corner.X=530|Corner.Y=520|LineWidth=1|Color=16711680
|RECORD=13|OwnerIndex=167|IsNotAccesible=T|IndexInSheet=21|OwnerPartId=1|Location.X=530|Location.Y=530|Corner.X=530|Corner.Y=527|Corner.Y_Frac=50000|LineWidth=1|Color=16711680
|RECORD=13|OwnerIndex=167|IsNotAccesible=T|IndexInSheet=22|OwnerPartId=1|Location.X=535|Location.Y=522|Location.Y_Frac=50000|Corner.X=525|Corner.Y=522|Corner.Y_Frac=50000|LineWidth=1|Color=16711680
|RECORD=13|OwnerIndex=167|IsNotAccesible=T|IndexInSheet=23|OwnerPartId=1|Location.X=535|Location.Y=527|Location.Y_Frac=50000|Corner.X=525|Corner.Y=527|Corner.Y_Frac=50000|LineWidth=1|Color=16711680
|RECORD=41|OwnerIndex=167|IndexInSheet=24|OwnerPartId=-1|Location.X=516|Location.Y=563|Location.Y_Frac=98951|Color=8388608|FontID=1|IsHidden=T|Text=<VALENTIUM>|Name=VALENTIUM PART NUM
|RECORD=34|OwnerIndex=167|IndexInSheet=-1|OwnerPartId=-1|Location.X=540|Location.Y=530|Color=8388608|FontID=1|Text=C5|Name=Designator|ReadOnlyState=1
|RECORD=41|OwnerIndex=167|IndexInSheet=-1|OwnerPartId=-1|Location.X=537|Location.X_Frac=50000|Location.Y=485|Color=8388608|FontID=1|IsHidden=T|Text=CAP_0805_10UF_25V|Name=Comment
|RECORD=44|OwnerIndex=167
|RECORD=45|OwnerIndex=197|IndexInSheet=-1|Description=Chip Capacitor, 0805, 2-Leads, Body 2.00x1.25mm, IPC Medium Density|UseComponentLibrary=T|ModelName=CAPC2012X14N|ModelType=PCBLIB|DatafileCount=1|ModelDatafileEntity0=CAPC2012X14N|ModelDatafileKind0=PCBLib|IsCurrent=T|DatalinksLocked=T|DatabaseDatalinksLocked=T|IntegratedModel=T|DatabaseModel=T
|RECORD=46|OwnerIndex=198
|RECORD=48|OwnerIndex=198
|RECORD=1|LibReference=CAP_0805_10UF_25V|ComponentDescription=CAP, CER, 10.UF, 25V, 10%, X5R, 0805|PartCount=2|DisplayModeCount=1|IndexInSheet=20|OwnerPartId=-1|Location.X=950|Location.Y=360|CurrentPartId=1|LibraryPath=*|SourceLibraryName=Capacitors.IntLib|TargetFileName=*|AreaColor=11599871|Color=128|PartIDLocked=F|DesignItemId=CAP_0805_10UF_25V|AllPinCount=2
|RECORD=41|OwnerIndex=201|OwnerPartId=-1|Location.X=950|Location.Y=360|Color=8388608|FontID=6|IsHidden=T|Text=TAIYO YUDEN|Name=MFG NAME
|RECORD=41|OwnerIndex=201|IndexInSheet=1|OwnerPartId=-1|Location.X=950|Location.Y=360|Color=8388608|FontID=6|IsHidden=T|Text=TMK212BBJ106KG-T|Name=MFG PART NUM
|RECORD=41|OwnerIndex=201|IndexInSheet=2|OwnerPartId=-1|Location.X=950|Location.Y=360|Color=8388608|FontID=6|IsHidden=T|Text=10/23/2013|Name=MODIFY DATE
|RECORD=41|OwnerIndex=201|IndexInSheet=3|OwnerPartId=-1|Location.X=950|Location.Y=360|Color=8388608|FontID=6|IsHidden=T|Text=CAP, CER|Name=CATEGORY
|RECORD=41|OwnerIndex=201|IndexInSheet=4|OwnerPartId=-1|Location.X=948|Location.Y=372|Location.Y_Frac=50000|Color=8388608|FontID=6|IsHidden=T|Text=4/11/2006 3:37:28 PM|Name=Date
|RECORD=41|OwnerIndex=201|IndexInSheet=5|OwnerPartId=-1|Location.X=956|Location.Y=434|Location.Y_Frac=48252|Color=8388608|FontID=6|IsHidden=T|Text=*|Name=SHEETPART
|RECORD=41|OwnerIndex=201|IndexInSheet=6|OwnerPartId=-1|Location.X=956|Location.Y=434|Location.Y_Frac=48252|Color=8388608|FontID=6|IsHidden=T|Text=10%|Name=P1
|RECORD=41|OwnerIndex=201|IndexInSheet=7|OwnerPartId=-1|Location.X=956|Location.Y=434|Location.Y_Frac=48252|Color=8388608|FontID=6|IsHidden=T|Text=85C|Name=MAXTEMP
|RECORD=41|OwnerIndex=201|IndexInSheet=8|OwnerPartId=-1|Location.X=956|Location.Y=434|Location.Y_Frac=48252|Color=8388608|FontID=6|IsHidden=T|Text=-55C|Name=MINTEMP
|RECORD=41|OwnerIndex=201|IndexInSheet=9|OwnerPartId=-1|Location.X=956|Location.Y=434|Location.Y_Frac=48252|Color=8388608|FontID=6|IsHidden=T|Name=OTHER
|RECORD=41|OwnerIndex=201|IndexInSheet=10|OwnerPartId=-1|Location.X=956|Location.Y=434|Location.Y_Frac=48252|Color=8388608|FontID=6|IsHidden=T|Text=25V|Name=P2
|RECORD=41|OwnerIndex=201|IndexInSheet=11|OwnerPartId=-1|Location.X=956|Location.Y=434|Location.Y_Frac=48252|Color=8388608|FontID=6|IsHidden=T|Text=X5R|Name=P3
|RECORD=41|OwnerIndex=201|IndexInSheet=12|OwnerPartId=-1|Location.X=956|Location.Y=434|Location.Y_Frac=48252|Color=8388608|FontID=6|IsHidden=T|Text=0805|Name=Size
|RECORD=41|OwnerIndex=201|IndexInSheet=13|OwnerPartId=-1|Location.X=956|Location.Y=434|Location.Y_Frac=48252|Color=8388608|FontID=6|IsHidden=T|Name=SUB
|RECORD=41|OwnerIndex=201|IndexInSheet=14|OwnerPartId=-1|Location.X=956|Location.Y=434|Location.Y_Frac=48252|Color=8388608|FontID=1|IsHidden=T|Text=CAP, CER, 10.UF, 10V, 10%, X5R, 0805|Name=DESC
|RECORD=41|OwnerIndex=201|IndexInSheet=15|OwnerPartId=-1|Location.X=956|Location.Y=433|Location.Y_Frac=98252|Color=8388608|FontID=1|IsHidden=T|Text=MOUSER|Name=Supplier 1|ReadOnlyState=1
|RECORD=41|OwnerIndex=201|IndexInSheet=16|OwnerPartId=-1|Location.X=956|Location.Y=433|Location.Y_Frac=98252|Color=8388608|FontID=1|IsHidden=T|Text=963-TMK212BBJ106KG-T|Name=Supplier Part Number 1|ReadOnlyState=1
|RECORD=41|OwnerIndex=201|IndexInSheet=17|OwnerPartId=-1|Location.X=980|Location.Y=390|Color=8388608|FontID=6|Text=10uF|Name=VALUE
|RECORD=2|OwnerIndex=201|OwnerPartId=1|FormalType=1|Electrical=4|PinConglomerate=35|PinLength=10|Location.X=970|Location.Y=390|Name=2|Designator=2|SwapIdPin=2|SwapIDPart=1|PinPropagationDelay=0.000000E+000
|RECORD=2|OwnerIndex=201|OwnerPartId=1|FormalType=1|Electrical=4|PinConglomerate=33|PinLength=10|Location.X=970|Location.Y=400|Name=1|Designator=1|SwapIdPin=1|SwapIDPart=1|PinPropagationDelay=0.000000E+000
|RECORD=13|OwnerIndex=201|IsNotAccesible=T|IndexInSheet=20|OwnerPartId=1|Location.X=970|Location.Y=392|Location.Y_Frac=50000|Corner.X=970|Corner.Y=390|LineWidth=1|Color=16711680
|RECORD=13|OwnerIndex=201|IsNotAccesible=T|IndexInSheet=21|OwnerPartId=1|Location.X=970|Location.Y=400|Corner.X=970|Corner.Y=397|Corner.Y_Frac=50000|LineWidth=1|Color=16711680
|RECORD=13|OwnerIndex=201|IsNotAccesible=T|IndexInSheet=22|OwnerPartId=1|Location.X=975|Location.Y=392|Location.Y_Frac=50000|Corner.X=965|Corner.Y=392|Corner.Y_Frac=50000|LineWidth=1|Color=16711680
|RECORD=13|OwnerIndex=201|IsNotAccesible=T|IndexInSheet=23|OwnerPartId=1|Location.X=975|Location.Y=397|Location.Y_Frac=50000|Corner.X=965|Corner.Y=397|Corner.Y_Frac=50000|LineWidth=1|Color=16711680
|RECORD=41|OwnerIndex=201|IndexInSheet=24|OwnerPartId=-1|Location.X=956|Location.Y=433|Location.Y_Frac=98951|Color=8388608|FontID=1|IsHidden=T|Text=<VALENTIUM>|Name=VALENTIUM PART NUM
|RECORD=34|OwnerIndex=201|IndexInSheet=-1|OwnerPartId=-1|Location.X=980|Location.Y=400|Color=8388608|FontID=1|Text=C7|Name=Designator|ReadOnlyState=1
|RECORD=41|OwnerIndex=201|IndexInSheet=-1|OwnerPartId=-1|Location.X=977|Location.X_Frac=50000|Location.Y=355|Color=8388608|FontID=1|IsHidden=T|Text=CAP_0805_10UF_25V|Name=Comment
|RECORD=44|OwnerIndex=201
|RECORD=45|OwnerIndex=231|IndexInSheet=-1|Description=Chip Capacitor, 0805, 2-Leads, Body 2.00x1.25mm, IPC Medium Density|UseComponentLibrary=T|ModelName=CAPC2012X14N|ModelType=PCBLIB|DatafileCount=1|ModelDatafileEntity0=CAPC2012X14N|ModelDatafileKind0=PCBLib|IsCurrent=T|DatalinksLocked=T|DatabaseDatalinksLocked=T|IntegratedModel=T|DatabaseModel=T
|RECORD=46|OwnerIndex=232
|RECORD=48|OwnerIndex=232
|RECORD=1|LibReference=CAP_0805_10UF_25V|ComponentDescription=CAP, CER, 10.UF, 25V, 10%, X5R, 0805|PartCount=2|DisplayModeCount=1|IndexInSheet=21|OwnerPartId=-1|Location.X=1000|Location.Y=360|CurrentPartId=1|LibraryPath=*|SourceLibraryName=Capacitors.IntLib|TargetFileName=*|AreaColor=11599871|Color=128|PartIDLocked=F|DesignItemId=CAP_0805_10UF_25V|AllPinCount=2
|RECORD=41|OwnerIndex=235|OwnerPartId=-1|Location.X=1000|Location.Y=360|Color=8388608|FontID=6|IsHidden=T|Text=TAIYO YUDEN|Name=MFG NAME
|RECORD=41|OwnerIndex=235|IndexInSheet=1|OwnerPartId=-1|Location.X=1000|Location.Y=360|Color=8388608|FontID=6|IsHidden=T|Text=TMK212BBJ106KG-T|Name=MFG PART NUM
|RECORD=41|OwnerIndex=235|IndexInSheet=2|OwnerPartId=-1|Location.X=1000|Location.Y=360|Color=8388608|FontID=6|IsHidden=T|Text=10/23/2013|Name=MODIFY DATE
|RECORD=41|OwnerIndex=235|IndexInSheet=3|OwnerPartId=-1|Location.X=1000|Location.Y=360|Color=8388608|FontID=6|IsHidden=T|Text=CAP, CER|Name=CATEGORY
|RECORD=41|OwnerIndex=235|IndexInSheet=4|OwnerPartId=-1|Location.X=998|Location.Y=372|Location.Y_Frac=50000|Color=8388608|FontID=6|IsHidden=T|Text=4/11/2006 3:37:28 PM|Name=Date
|RECORD=41|OwnerIndex=235|IndexInSheet=5|OwnerPartId=-1|Location.X=1006|Location.Y=434|Location.Y_Frac=48252|Color=8388608|FontID=6|IsHidden=T|Text=*|Name=SHEETPART
|RECORD=41|OwnerIndex=235|IndexInSheet=6|OwnerPartId=-1|Location.X=1006|Location.Y=434|Location.Y_Frac=48252|Color=8388608|FontID=6|IsHidden=T|Text=10%|Name=P1
|RECORD=41|OwnerIndex=235|IndexInSheet=7|OwnerPartId=-1|Location.X=1006|Location.Y=434|Location.Y_Frac=48252|Color=8388608|FontID=6|IsHidden=T|Text=85C|Name=MAXTEMP
|RECORD=41|OwnerIndex=235|IndexInSheet=8|OwnerPartId=-1|Location.X=1006|Location.Y=434|Location.Y_Frac=48252|Color=8388608|FontID=6|IsHidden=T|Text=-55C|Name=MINTEMP
|RECORD=41|OwnerIndex=235|IndexInSheet=9|OwnerPartId=-1|Location.X=1006|Location.Y=434|Location.Y_Frac=48252|Color=8388608|FontID=6|IsHidden=T|Name=OTHER
|RECORD=41|OwnerIndex=235|IndexInSheet=10|OwnerPartId=-1|Location.X=1006|Location.Y=434|Location.Y_Frac=48252|Color=8388608|FontID=6|IsHidden=T|Text=25V|Name=P2
|RECORD=41|OwnerIndex=235|IndexInSheet=11|OwnerPartId=-1|Location.X=1006|Location.Y=434|Location.Y_Frac=48252|Color=8388608|FontID=6|IsHidden=T|Text=X5R|Name=P3
|RECORD=41|OwnerIndex=235|IndexInSheet=12|OwnerPartId=-1|Location.X=1006|Location.Y=434|Location.Y_Frac=48252|Color=8388608|FontID=6|IsHidden=T|Text=0805|Name=Size
|RECORD=41|OwnerIndex=235|IndexInSheet=13|OwnerPartId=-1|Location.X=1006|Location.Y=434|Location.Y_Frac=48252|Color=8388608|FontID=6|IsHidden=T|Name=SUB
|RECORD=41|OwnerIndex=235|IndexInSheet=14|OwnerPartId=-1|Location.X=1006|Location.Y=434|Location.Y_Frac=48252|Color=8388608|FontID=1|IsHidden=T|Text=CAP, CER, 10.UF, 10V, 10%, X5R, 0805|Name=DESC
|RECORD=41|OwnerIndex=235|IndexInSheet=15|OwnerPartId=-1|Location.X=1006|Location.Y=433|Location.Y_Frac=98252|Color=8388608|FontID=1|IsHidden=T|Text=MOUSER|Name=Supplier 1|ReadOnlyState=1
|RECORD=41|OwnerIndex=235|IndexInSheet=16|OwnerPartId=-1|Location.X=1006|Location.Y=433|Location.Y_Frac=98252|Color=8388608|FontID=1|IsHidden=T|Text=963-TMK212BBJ106KG-T|Name=Supplier Part Number 1|ReadOnlyState=1
|RECORD=41|OwnerIndex=235|IndexInSheet=17|OwnerPartId=-1|Location.X=1030|Location.Y=390|Color=8388608|FontID=6|Text=10uF|Name=VALUE
|RECORD=2|OwnerIndex=235|OwnerPartId=1|FormalType=1|Electrical=4|PinConglomerate=35|PinLength=10|Location.X=1020|Location.Y=390|Name=2|Designator=2|SwapIdPin=2|SwapIDPart=1|PinPropagationDelay=0.000000E+000
|RECORD=2|OwnerIndex=235|OwnerPartId=1|FormalType=1|Electrical=4|PinConglomerate=33|PinLength=10|Location.X=1020|Location.Y=400|Name=1|Designator=1|SwapIdPin=1|SwapIDPart=1|PinPropagationDelay=0.000000E+000
|RECORD=13|OwnerIndex=235|IsNotAccesible=T|IndexInSheet=20|OwnerPartId=1|Location.X=1020|Location.Y=392|Location.Y_Frac=50000|Corner.X=1020|Corner.Y=390|LineWidth=1|Color=16711680
|RECORD=13|OwnerIndex=235|IsNotAccesible=T|IndexInSheet=21|OwnerPartId=1|Location.X=1020|Location.Y=400|Corner.X=1020|Corner.Y=397|Corner.Y_Frac=50000|LineWidth=1|Color=16711680
|RECORD=13|OwnerIndex=235|IsNotAccesible=T|IndexInSheet=22|OwnerPartId=1|Location.X=1025|Location.Y=392|Location.Y_Frac=50000|Corner.X=1015|Corner.Y=392|Corner.Y_Frac=50000|LineWidth=1|Color=16711680
|RECORD=13|OwnerIndex=235|IsNotAccesible=T|IndexInSheet=23|OwnerPartId=1|Location.X=1025|Location.Y=397|Location.Y_Frac=50000|Corner.X=1015|Corner.Y=397|Corner.Y_Frac=50000|LineWidth=1|Color=16711680
|RECORD=41|OwnerIndex=235|IndexInSheet=24|OwnerPartId=-1|Location.X=1006|Location.Y=433|Location.Y_Frac=98951|Color=8388608|FontID=1|IsHidden=T|Text=<VALENTIUM>|Name=VALENTIUM PART NUM
|RECORD=34|OwnerIndex=235|IndexInSheet=-1|OwnerPartId=-1|Location.X=1030|Location.Y=400|Color=8388608|FontID=1|Text=C8|Name=Designator|ReadOnlyState=1
|RECORD=41|OwnerIndex=235|IndexInSheet=-1|OwnerPartId=-1|Location.X=1027|Location.X_Frac=50000|Location.Y=355|Color=8388608|FontID=1|IsHidden=T|Text=CAP_0805_10UF_25V|Name=Comment
|RECORD=44|OwnerIndex=235
|RECORD=45|OwnerIndex=265|IndexInSheet=-1|Description=Chip Capacitor, 0805, 2-Leads, Body 2.00x1.25mm, IPC Medium Density|UseComponentLibrary=T|ModelName=CAPC2012X14N|ModelType=PCBLIB|DatafileCount=1|ModelDatafileEntity0=CAPC2012X14N|ModelDatafileKind0=PCBLib|IsCurrent=T|DatalinksLocked=T|DatabaseDatalinksLocked=T|IntegratedModel=T|DatabaseModel=T
|RECORD=46|OwnerIndex=266
|RECORD=48|OwnerIndex=266
|RECORD=1|LibReference=SMTLED_RED_0603_SML|ComponentDescription=LED, RED, SML-LX0603, 635NM, 2V, 20MA, 0603|PartCount=2|DisplayModeCount=1|IndexInSheet=22|OwnerPartId=-1|Location.X=1330|Location.Y=430|Orientation=3|CurrentPartId=1|LibraryPath=*|SourceLibraryName=Passives.IntLib|TargetFileName=*|AreaColor=11599871|Color=128|PartIDLocked=F|DesignItemId=SMTLED_RED_0603_SML|AllPinCount=2
|RECORD=41|OwnerIndex=269|OwnerPartId=-1|Location.X=1317|Location.X_Frac=50000|Location.Y=432|Color=8388608|FontID=6|IsHidden=T|Text=SML-LX0603IW-TR|Name=MFG PART NUM
|RECORD=41|OwnerIndex=269|IndexInSheet=1|OwnerPartId=-1|Location.X=1317|Location.X_Frac=50000|Location.Y=432|Color=8388608|FontID=6|IsHidden=T|Text=9/4/2013|Name=MODIFY DATE
|RECORD=41|OwnerIndex=269|IndexInSheet=2|OwnerPartId=-1|Location.X=1317|Location.X_Frac=50000|Location.Y=432|Color=8388608|FontID=6|IsHidden=T|Text=LUMEX|Name=MFG NAME
|RECORD=41|OwnerIndex=269|IndexInSheet=3|OwnerPartId=-1|Location.X=1317|Location.X_Frac=50000|Location.Y=432|Color=8388608|FontID=6|IsHidden=T|Text=LED|Name=CATEGORY
|RECORD=41|OwnerIndex=269|IndexInSheet=4|OwnerPartId=-1|Location.X=1317|Location.X_Frac=50000|Location.Y=432|Color=8388608|FontID=6|IsHidden=T|Name=Date
|RECORD=41|OwnerIndex=269|IndexInSheet=5|OwnerPartId=-1|Location.X=1317|Location.X_Frac=50000|Location.Y=432|Color=8388608|FontID=6|IsHidden=T|Text=85C|Name=MAXTEMP
|RECORD=41|OwnerIndex=269|IndexInSheet=6|OwnerPartId=-1|Location.X=1317|Location.X_Frac=50000|Location.Y=432|Color=8388608|FontID=6|IsHidden=T|Text=-25C|Name=MINTEMP
|RECORD=41|OwnerIndex=269|IndexInSheet=7|OwnerPartId=-1|Location.X=1317|Location.X_Frac=50000|Location.Y=432|Color=8388608|FontID=6|IsHidden=T|Text=SML-LX0603|Name=OTHER
|RECORD=41|OwnerIndex=269|IndexInSheet=8|OwnerPartId=-1|Location.X=1317|Location.X_Frac=50000|Location.Y=432|Color=8388608|FontID=6|IsHidden=T|Text=635NM|Name=P1
|RECORD=41|OwnerIndex=269|IndexInSheet=9|OwnerPartId=-1|Location.X=1317|Location.X_Frac=50000|Location.Y=432|Color=8388608|FontID=6|IsHidden=T|Text=2V|Name=P2
|RECORD=41|OwnerIndex=269|IndexInSheet=10|OwnerPartId=-1|Location.X=1317|Location.X_Frac=50000|Location.Y=432|Color=8388608|FontID=6|IsHidden=T|Text=20MA|Name=P3
|RECORD=41|OwnerIndex=269|IndexInSheet=11|OwnerPartId=-1|Location.X=1317|Location.X_Frac=50000|Location.Y=432|Color=8388608|FontID=6|IsHidden=T|Name=SUB
|RECORD=41|OwnerIndex=269|IndexInSheet=12|OwnerPartId=-1|Location.X=1317|Location.X_Frac=50000|Location.Y=432|Color=8388608|FontID=6|IsHidden=T|Text=0603|Name=SIZE
|RECORD=41|OwnerIndex=269|IndexInSheet=13|OwnerPartId=-1|Location.X=1317|Location.X_Frac=50000|Location.Y=432|Color=8388608|FontID=1|IsHidden=T|Text=*|Name=SHEETPART
|RECORD=41|OwnerIndex=269|IndexInSheet=14|OwnerPartId=-1|Location.X=1317|Location.X_Frac=50000|Location.Y=432|Color=8388608|FontID=1|IsHidden=T|Text=LED, RED, SML-LX0603, 635NM, 2V, 20MA, 0603|Name=DESC
|RECORD=41|OwnerIndex=269|IndexInSheet=15|OwnerPartId=-1|Location.X=1317|Location.X_Frac=50000|Location.Y=432|Color=8388608|FontID=1|IsHidden=T|Text=Digi-Key|Name=Supplier 1|ReadOnlyState=3
|RECORD=41|OwnerIndex=269|IndexInSheet=16|OwnerPartId=-1|Location.X=1317|Location.X_Frac=50000|Location.Y=432|Color=8388608|FontID=1|IsHidden=T|Text=67-1548-1-ND|Name=Supplier Part Number 1|ReadOnlyState=3
|RECORD=41|OwnerIndex=269|IndexInSheet=17|OwnerPartId=-1|Location.X=1350|Location.Y=386|Location.Y_Frac=50000|Color=8388608|FontID=6|Text=RED|Name=VALUE
|RECORD=2|OwnerIndex=269|OwnerPartId=1|FormalType=1|Electrical=4|PinConglomerate=33|PinLength=20|Location.X=1330|Location.Y=410|Name=A|Designator=2|PinPropagationDelay=0.000000E+000
|RECORD=2|OwnerIndex=269|OwnerPartId=1|FormalType=1|Electrical=4|PinConglomerate=35|PinLength=20|Location.X=1330|Location.Y=390|Name=K|Designator=1|PinPropagationDelay=0.000000E+000
|RECORD=12|OwnerIndex=269|IsNotAccesible=T|IndexInSheet=20|OwnerPartId=1|Location.X=1330|Location.Y=400|Radius=12|Radius_Frac=50000|LineWidth=1|EndAngle=360.000|Color=16711680
|RECORD=13|OwnerIndex=269|IsNotAccesible=T|IndexInSheet=21|OwnerPartId=1|Location.X=1338|Location.Y=394|Corner.X=1323|Corner.Y=394|LineWidth=1|Color=16711680
|RECORD=13|OwnerIndex=269|IsNotAccesible=T|IndexInSheet=22|OwnerPartId=1|Location.X=1345|Location.Y=381|Corner.X=1338|Corner.X_Frac=70000|Corner.Y=387|Corner.Y_Frac=20000|LineWidth=1|Color=16711680
|RECORD=13|OwnerIndex=269|IsNotAccesible=T|IndexInSheet=23|OwnerPartId=1|Location.X=1349|Location.Y=385|Corner.X=1342|Corner.X_Frac=80000|Corner.Y=391|Corner.Y_Frac=30000|LineWidth=1|Color=16711680
|RECORD=13|OwnerIndex=269|IsNotAccesible=T|IndexInSheet=24|OwnerPartId=1|Location.X=1330|Location.Y=390|Corner.X=1330|Corner.Y=393|Corner.Y_Frac=80000|LineWidth=1|Color=16711680
|RECORD=13|OwnerIndex=269|IsNotAccesible=T|IndexInSheet=25|OwnerPartId=1|Location.X=1330|Location.Y=406|Corner.X=1330|Corner.Y=409|Corner.Y_Frac=70000|LineWidth=1|Color=16711680
|RECORD=7|OwnerIndex=269|IsNotAccesible=T|IndexInSheet=26|OwnerPartId=1|LineWidth=1|Color=16711680|AreaColor=16711680|IsSolid=T|LocationCount=3|X1=1344|Y1=384|X2=1342|Y2=382|X3=1345|Y3=381
|RECORD=7|OwnerIndex=269|IsNotAccesible=T|IndexInSheet=27|OwnerPartId=1|LineWidth=1|Color=16711680|AreaColor=16711680|IsSolid=T|LocationCount=3|X1=1348|Y1=388|X2=1346|Y2=386|X3=1349|Y3=385
|RECORD=7|OwnerIndex=269|IsNotAccesible=T|IndexInSheet=28|OwnerPartId=1|LineWidth=1|Color=16711680|AreaColor=16777215|IsSolid=T|LocationCount=3|X1=1330|Y1=394|X2=1338|Y2=406|X3=1322|Y3=406
|RECORD=41|OwnerIndex=269|IndexInSheet=29|OwnerPartId=-1|Location.X=1317|Location.X_Frac=50000|Location.Y=432|Color=8388608|FontID=1|IsHidden=T|Text=<VALENTIUM>|Name=VALENTIUM PART NUM
|RECORD=34|OwnerIndex=269|IndexInSheet=-1|OwnerPartId=-1|Location.X=1350|Location.Y=398|Location.Y_Frac=50000|Color=8388608|FontID=1|Text=D4|Name=Designator|ReadOnlyState=1
|RECORD=41|OwnerIndex=269|IndexInSheet=-1|OwnerPartId=-1|Location.X=1317|Location.X_Frac=50000|Location.Y=432|Color=8388608|FontID=1|IsHidden=T|Text==VALUE|Name=Comment|ReadOnlyState=1
|RECORD=44|OwnerIndex=269
|RECORD=45|OwnerIndex=304|IndexInSheet=-1|Description=Molded Diode, 0603, 2-Leads, Body 1.60x0.80mm, IPC Medium Density|UseComponentLibrary=T|ModelName=DIOM1608X06N|ModelType=PCBLIB|DatafileCount=1|ModelDatafileEntity0=DIOM1608X06N|ModelDatafileKind0=PCBLib|IsCurrent=T|DatalinksLocked=T|DatabaseDatalinksLocked=T|IntegratedModel=T|DatabaseModel=T
|RECORD=46|OwnerIndex=305
|RECORD=48|OwnerIndex=305
|RECORD=1|LibReference=RES_0603_200|ComponentDescription=RES, 200 OHM, 1%, 1/10W, TF, 0603|PartCount=2|DisplayModeCount=1|IndexInSheet=23|OwnerPartId=-1|Location.X=1330|Location.Y=300|Orientation=1|CurrentPartId=1|LibraryPath=*|SourceLibraryName=Resistors.IntLib|TargetFileName=*|AreaColor=11599871|Color=128|PartIDLocked=F|DesignItemId=RES_0603_200|AllPinCount=2
|RECORD=41|OwnerIndex=308|OwnerPartId=-1|Location.X=1326|Location.Y=352|Color=8388608|FontID=6|IsHidden=T|Text=7/25/2013|Name=ModifyDate
|RECORD=41|OwnerIndex=308|IndexInSheet=1|OwnerPartId=-1|Location.X=1326|Location.Y=352|Color=8388608|FontID=6|IsHidden=T|Text=ERJ-3EKF2000V|Name=MFG PART NUM
|RECORD=41|OwnerIndex=308|IndexInSheet=2|OwnerPartId=-1|Location.X=1326|Location.Y=352|Color=8388608|FontID=6|IsHidden=T|Text=PANASONIC|Name=MFG NAME
|RECORD=41|OwnerIndex=308|IndexInSheet=3|OwnerPartId=-1|Location.X=1326|Location.Y=352|Color=8388608|FontID=6|IsHidden=T|Text=RES|Name=CATEGORY
|RECORD=41|OwnerIndex=308|IndexInSheet=4|OwnerPartId=-1|Location.X=1326|Location.Y=352|Color=8388608|FontID=6|IsHidden=T|Text=7/26/2013|Name=Date
|RECORD=41|OwnerIndex=308|IndexInSheet=5|OwnerPartId=-1|Location.X=1326|Location.Y=352|Color=8388608|FontID=6|IsHidden=T|Text=1%|Name=P1
|RECORD=41|OwnerIndex=308|IndexInSheet=6|OwnerPartId=-1|Location.X=1326|Location.Y=352|Color=8388608|FontID=6|IsHidden=T|Text=TF|Name=P3
|RECORD=41|OwnerIndex=308|IndexInSheet=7|OwnerPartId=-1|Location.X=1326|Location.Y=352|Color=8388608|FontID=6|IsHidden=T|Text=1/10W|Name=P2
|RECORD=41|OwnerIndex=308|IndexInSheet=8|OwnerPartId=-1|Location.X=1326|Location.Y=352|Color=8388608|FontID=6|IsHidden=T|Text=125C|Name=MAXTEMP
|RECORD=41|OwnerIndex=308|IndexInSheet=9|OwnerPartId=-1|Location.X=1326|Location.Y=352|Color=8388608|FontID=6|IsHidden=T|Text=-55C|Name=MINTEMP
|RECORD=41|OwnerIndex=308|IndexInSheet=10|OwnerPartId=-1|Location.X=1326|Location.Y=352|Color=8388608|FontID=6|IsHidden=T|Text=100PPM|Name=OTHER
|RECORD=41|OwnerIndex=308|IndexInSheet=11|OwnerPartId=-1|Location.X=1326|Location.Y=352|Color=8388608|FontID=6|IsHidden=T|Text=0603|Name=SIZE
|RECORD=41|OwnerIndex=308|IndexInSheet=12|OwnerPartId=-1|Location.X=1326|Location.Y=352|Color=8388608|FontID=6|IsHidden=T|Text=GENERIC|Name=SUB
|RECORD=41|OwnerIndex=308|IndexInSheet=13|OwnerPartId=-1|Location.X=1326|Location.Y=352|Color=8388608|FontID=1|IsHidden=T|Text=*|Name=SHEETPART
|RECORD=41|OwnerIndex=308|IndexInSheet=14|OwnerPartId=-1|Location.X=1326|Location.Y=352|Color=8388608|FontID=1|IsHidden=T|Text=RES, 200 OHM, 1%, 1/10W, TF, 0603|Name=DESC
|RECORD=41|OwnerIndex=308|IndexInSheet=15|OwnerPartId=-1|Location.X=1326|Location.Y=352|Color=8388608|FontID=1|IsHidden=T|Text=Digi-Key|Name=Supplier 1|ReadOnlyState=3
|RECORD=41|OwnerIndex=308|IndexInSheet=16|OwnerPartId=-1|Location.X=1326|Location.Y=352|Color=8388608|FontID=1|IsHidden=T|Text=P200HCT-ND|Name=Supplier Part Number 1|ReadOnlyState=3
|RECORD=41|OwnerIndex=308|IndexInSheet=17|OwnerPartId=-1|Location.X=1326|Location.Y=352|Color=8388608|FontID=1|IsHidden=T|Text=<VELENTIUM>|Name=VELENTIUM PART NUM
|RECORD=41|OwnerIndex=308|IndexInSheet=18|OwnerPartId=-1|Location.X=1334|Location.Y=315|Color=8388608|FontID=6|Text=200 OHM|Name=VALUE
|RECORD=2|OwnerIndex=308|OwnerPartId=1|FormalType=1|Electrical=4|PinConglomerate=35|PinLength=10|Location.X=1330|Location.Y=310|Name=1|Designator=1|PinPropagationDelay=0.000000E+000
|RECORD=2|OwnerIndex=308|OwnerPartId=1|FormalType=1|Electrical=4|PinConglomerate=33|PinLength=10|Location.X=1330|Location.Y=340|Name=2|Designator=2|PinPropagationDelay=0.000000E+000
|RECORD=6|OwnerIndex=308|IsNotAccesible=T|IndexInSheet=21|OwnerPartId=1|LineWidth=1|Color=16711680|LocationCount=7|X1=1330|Y1=340|X2=1327|Y2=337|X3=1333|Y3=331|X4=1327|Y4=325|X5=1333|Y5=319|X6=1327|Y6=313|X7=1330|Y7=310
|RECORD=34|OwnerIndex=308|IndexInSheet=-1|OwnerPartId=-1|Location.X=1334|Location.Y=327|Color=8388608|FontID=1|Text=R1|Name=Designator|ReadOnlyState=1
|RECORD=41|OwnerIndex=308|IndexInSheet=-1|OwnerPartId=-1|Location.X=1326|Location.Y=352|Color=8388608|FontID=1|IsHidden=T|Text==MFG PART NUM|Name=Comment
|RECORD=44|OwnerIndex=308
|RECORD=45|OwnerIndex=335|IndexInSheet=-1|Description=Chip Resistor, 0603, 2-Leads, Body 1.57x0.85mm, IPC Medium Density|UseComponentLibrary=T|ModelName=RESC1608X50N|ModelType=PCBLIB|DatafileCount=1|ModelDatafileEntity0=RESC1608X50N|ModelDatafileKind0=PCBLib|IsCurrent=T|DatalinksLocked=T|DatabaseDatalinksLocked=T|IntegratedModel=T|DatabaseModel=T
|RECORD=46|OwnerIndex=336
|RECORD=48|OwnerIndex=336
|RECORD=1|LibReference=RES_0603_47K|ComponentDescription=RES, 47K, 1%, 1/10W, TF, 0603|PartCount=2|DisplayModeCount=1|IndexInSheet=24|OwnerPartId=-1|Location.X=590|Location.Y=900|Orientation=1|CurrentPartId=1|LibraryPath=*|SourceLibraryName=Resistors.IntLib|TargetFileName=*|AreaColor=11599871|Color=128|PartIDLocked=F|DesignItemId=RES_0603_47K|AllPinCount=2
|RECORD=41|OwnerIndex=339|OwnerPartId=-1|Location.X=586|Location.Y=952|Color=8388608|FontID=6|IsHidden=T|Text=1/22/2014|Name=ModifyDate
|RECORD=41|OwnerIndex=339|IndexInSheet=1|OwnerPartId=-1|Location.X=586|Location.Y=952|Color=8388608|FontID=6|IsHidden=T|Text=ERJ-3EKF4702V|Name=MFG PART NUM
|RECORD=41|OwnerIndex=339|IndexInSheet=2|OwnerPartId=-1|Location.X=586|Location.Y=952|Color=8388608|FontID=6|IsHidden=T|Text=PANASONIC|Name=MFG NAME
|RECORD=41|OwnerIndex=339|IndexInSheet=3|OwnerPartId=-1|Location.X=586|Location.Y=952|Color=8388608|FontID=6|IsHidden=T|Text=RES|Name=CATEGORY
|RECORD=41|OwnerIndex=339|IndexInSheet=4|OwnerPartId=-1|Location.X=586|Location.Y=952|Color=8388608|FontID=6|IsHidden=T|Text=1/22/2014|Name=Date
|RECORD=41|OwnerIndex=339|IndexInSheet=5|OwnerPartId=-1|Location.X=586|Location.Y=952|Color=8388608|FontID=6|IsHidden=T|Text=1%|Name=P1
|RECORD=41|OwnerIndex=339|IndexInSheet=6|OwnerPartId=-1|Location.X=586|Location.Y=952|Color=8388608|FontID=6|IsHidden=T|Text=TF|Name=P3
|RECORD=41|OwnerIndex=339|IndexInSheet=7|OwnerPartId=-1|Location.X=586|Location.Y=952|Color=8388608|FontID=6|IsHidden=T|Text=1/10W|Name=P2
|RECORD=41|OwnerIndex=339|IndexInSheet=8|OwnerPartId=-1|Location.X=586|Location.Y=952|Color=8388608|FontID=6|IsHidden=T|Text=125C|Name=MAXTEMP
|RECORD=41|OwnerIndex=339|IndexInSheet=9|OwnerPartId=-1|Location.X=586|Location.Y=952|Color=8388608|FontID=6|IsHidden=T|Text=-55C|Name=MINTEMP
|RECORD=41|OwnerIndex=339|IndexInSheet=10|OwnerPartId=-1|Location.X=586|Location.Y=952|Color=8388608|FontID=6|IsHidden=T|Text=100PPM|Name=OTHER
|RECORD=41|OwnerIndex=339|IndexInSheet=11|OwnerPartId=-1|Location.X=586|Location.Y=952|Color=8388608|FontID=6|IsHidden=T|Text=0603|Name=SIZE
|RECORD=41|OwnerIndex=339|IndexInSheet=12|OwnerPartId=-1|Location.X=586|Location.Y=952|Color=8388608|FontID=6|IsHidden=T|Text=GENERIC|Name=SUB
|RECORD=41|OwnerIndex=339|IndexInSheet=13|OwnerPartId=-1|Location.X=586|Location.Y=952|Color=8388608|FontID=1|IsHidden=T|Text=*|Name=SHEETPART
|RECORD=41|OwnerIndex=339|IndexInSheet=14|OwnerPartId=-1|Location.X=586|Location.Y=952|Color=8388608|FontID=1|IsHidden=T|Text=RES, 47K, 1%, 1/10W, TF, 0603|Name=DESC
|RECORD=41|OwnerIndex=339|IndexInSheet=15|OwnerPartId=-1|Location.X=586|Location.Y=952|Color=8388608|FontID=1|IsHidden=T|Text=Digi-Key|Name=Supplier 1|ReadOnlyState=3
|RECORD=41|OwnerIndex=339|IndexInSheet=16|OwnerPartId=-1|Location.X=586|Location.Y=952|Color=8388608|FontID=1|IsHidden=T|Text=P47.0KHCT-ND|Name=Supplier Part Number 1|ReadOnlyState=3
|RECORD=41|OwnerIndex=339|IndexInSheet=17|OwnerPartId=-1|Location.X=594|Location.Y=915|Color=8388608|FontID=6|Text=47K|Name=VALUE
|RECORD=2|OwnerIndex=339|OwnerPartId=1|FormalType=1|Electrical=4|PinConglomerate=35|PinLength=10|Location.X=590|Location.Y=910|Name=1|Designator=1|PinPropagationDelay=0.000000E+000
|RECORD=2|OwnerIndex=339|OwnerPartId=1|FormalType=1|Electrical=4|PinConglomerate=33|PinLength=10|Location.X=590|Location.Y=940|Name=2|Designator=2|PinPropagationDelay=0.000000E+000
|RECORD=6|OwnerIndex=339|IsNotAccesible=T|IndexInSheet=20|OwnerPartId=1|LineWidth=1|Color=16711680|LocationCount=7|X1=590|Y1=940|X2=587|Y2=937|X3=593|Y3=931|X4=587|Y4=925|X5=593|Y5=919|X6=587|Y6=913|X7=590|Y7=910
|RECORD=41|OwnerIndex=339|IndexInSheet=21|OwnerPartId=-1|Location.X=586|Location.Y=952|Color=8388608|FontID=1|IsHidden=T|Text=<VELENTIUM>|Name=VELENTIUM PART NUM
|RECORD=34|OwnerIndex=339|IndexInSheet=-1|OwnerPartId=-1|Location.X=594|Location.Y=927|Color=8388608|FontID=1|Text=R2|Name=Designator|ReadOnlyState=1
|RECORD=41|OwnerIndex=339|IndexInSheet=-1|OwnerPartId=-1|Location.X=586|Location.Y=952|Color=8388608|FontID=1|IsHidden=T|Text==MFG PART NUM|Name=Comment
|RECORD=44|OwnerIndex=339
|RECORD=45|OwnerIndex=366|IndexInSheet=-1|Description=Chip Resistor, 0603, 2-Leads, Body 1.57x0.85mm, IPC Medium Density|UseComponentLibrary=T|ModelName=RESC1608X50N|ModelType=PCBLIB|DatafileCount=1|ModelDatafileEntity0=RESC1608X50N|ModelDatafileKind0=PCBLib|IsCurrent=T|DatalinksLocked=T|DatabaseDatalinksLocked=T|IntegratedModel=T|DatabaseModel=T
|RECORD=46|OwnerIndex=367
|RECORD=48|OwnerIndex=367
|RECORD=1|LibReference=RES_0603_2.2K|ComponentDescription=RES, 2.2K, 1%, 1/10W, TF, 0603|PartCount=2|DisplayModeCount=1|IndexInSheet=25|OwnerPartId=-1|Location.X=690|Location.Y=730|CurrentPartId=1|LibraryPath=*|SourceLibraryName=Resistors.IntLib|TargetFileName=*|AreaColor=11599871|Color=128|PartIDLocked=F|DesignItemId=RES_0603_2.2K|AllPinCount=2
|RECORD=41|OwnerIndex=370|OwnerPartId=-1|Location.X=690|Location.Y=730|Color=8388608|FontID=6|IsHidden=T|Text=8/15/2013|Name=ModifyDate
|RECORD=41|OwnerIndex=370|IndexInSheet=1|OwnerPartId=-1|Location.X=690|Location.Y=730|Color=8388608|FontID=6|IsHidden=T|Text=ERJ-3EKF2201V|Name=MFG PART NUM
|RECORD=41|OwnerIndex=370|IndexInSheet=2|OwnerPartId=-1|Location.X=690|Location.Y=730|Color=8388608|FontID=6|IsHidden=T|Text=PANASONIC|Name=MFG NAME
|RECORD=41|OwnerIndex=370|IndexInSheet=3|OwnerPartId=-1|Location.X=690|Location.Y=730|Color=8388608|FontID=6|IsHidden=T|Text=RES|Name=CATEGORY
|RECORD=41|OwnerIndex=370|IndexInSheet=4|OwnerPartId=-1|Location.X=688|Location.Y=740|Color=8388608|FontID=6|IsHidden=T|Text=8/15/2013|Name=Date
|RECORD=41|OwnerIndex=370|IndexInSheet=5|OwnerPartId=-1|Location.X=680|Location.X_Frac=55769|Location.Y=740|Color=8388608|FontID=6|IsHidden=T|Text=1%|Name=P1
|RECORD=41|OwnerIndex=370|IndexInSheet=6|OwnerPartId=-1|Location.X=680|Location.X_Frac=55769|Location.Y=740|Color=8388608|FontID=6|IsHidden=T|Text=TF|Name=P3
|RECORD=41|OwnerIndex=370|IndexInSheet=7|OwnerPartId=-1|Location.X=680|Location.X_Frac=55769|Location.Y=740|Color=8388608|FontID=6|IsHidden=T|Text=1/10W|Name=P2
|RECORD=41|OwnerIndex=370|IndexInSheet=8|OwnerPartId=-1|Location.X=680|Location.X_Frac=55769|Location.Y=740|Color=8388608|FontID=6|IsHidden=T|Text=125C|Name=MAXTEMP
|RECORD=41|OwnerIndex=370|IndexInSheet=9|OwnerPartId=-1|Location.X=680|Location.X_Frac=55769|Location.Y=740|Color=8388608|FontID=6|IsHidden=T|Text=-55C|Name=MINTEMP
|RECORD=41|OwnerIndex=370|IndexInSheet=10|OwnerPartId=-1|Location.X=680|Location.X_Frac=55769|Location.Y=740|Color=8388608|FontID=6|IsHidden=T|Text=100PPM|Name=OTHER
|RECORD=41|OwnerIndex=370|IndexInSheet=11|OwnerPartId=-1|Location.X=680|Location.X_Frac=55769|Location.Y=740|Color=8388608|FontID=6|IsHidden=T|Text=0603|Name=SIZE
|RECORD=41|OwnerIndex=370|IndexInSheet=12|OwnerPartId=-1|Location.X=680|Location.X_Frac=55769|Location.Y=740|Color=8388608|FontID=6|IsHidden=T|Text=GENERIC|Name=SUB
|RECORD=41|OwnerIndex=370|IndexInSheet=13|OwnerPartId=-1|Location.X=675|Location.X_Frac=98077|Location.Y=744|Color=8388608|FontID=6|IsHidden=T|Text=Digi-Key|Name=Supplier 1|ReadOnlyState=3
|RECORD=41|OwnerIndex=370|IndexInSheet=14|OwnerPartId=-1|Location.X=675|Location.X_Frac=98077|Location.Y=744|Color=8388608|FontID=6|IsHidden=T|Text=P2.20KHCT-ND|Name=Supplier Part Number 1|ReadOnlyState=3
|RECORD=41|OwnerIndex=370|IndexInSheet=15|OwnerPartId=-1|Location.X=675|Location.X_Frac=98077|Location.Y=716|Color=8388608|FontID=1|IsHidden=T|Text=*|Name=SHEETPART
|RECORD=41|OwnerIndex=370|IndexInSheet=16|OwnerPartId=-1|Location.X=675|Location.X_Frac=98077|Location.Y=744|Color=8388608|FontID=1|IsHidden=T|Text=RES, 2.2K, 1%, 1/10W, TF, 0603|Name=DESC
|RECORD=41|OwnerIndex=370|IndexInSheet=17|OwnerPartId=-1|Location.X=699|Location.Y=714|Color=8388608|FontID=6|Text=2.2K|Name=VALUE
|RECORD=2|OwnerIndex=370|OwnerPartId=1|FormalType=1|Electrical=4|PinConglomerate=34|PinLength=10|Location.X=700|Location.Y=730|Name=1|Designator=1|PinPropagationDelay=0.000000E+000
|RECORD=2|OwnerIndex=370|OwnerPartId=1|FormalType=1|Electrical=4|PinConglomerate=32|PinLength=10|Location.X=730|Location.Y=730|Name=2|Designator=2|PinPropagationDelay=0.000000E+000
|RECORD=6|OwnerIndex=370|IsNotAccesible=T|IndexInSheet=20|OwnerPartId=1|LineWidth=1|Color=16711680|LocationCount=7|X1=730|Y1=730|X2=727|Y2=733|X3=721|Y3=727|X4=715|Y4=733|X5=709|Y5=727|X6=703|Y6=733|X7=700|Y7=730
|RECORD=41|OwnerIndex=370|IndexInSheet=21|OwnerPartId=-1|Location.X=676|Location.X_Frac=61102|Location.Y=744|Color=8388608|FontID=1|IsHidden=T|Text=<VELENTIUM>|Name=VELENTIUM PART NUM
|RECORD=34|OwnerIndex=370|IndexInSheet=-1|OwnerPartId=-1|Location.X=699|Location.Y=734|Color=8388608|FontID=1|Text=R8|Name=Designator|ReadOnlyState=1
|RECORD=41|OwnerIndex=370|IndexInSheet=-1|OwnerPartId=-1|Location.X=710|Location.Y=720|Color=8388608|FontID=1|IsHidden=T|Text==MFG PART NUM|Name=Comment
|RECORD=44|OwnerIndex=370
|RECORD=45|OwnerIndex=397|IndexInSheet=-1|Description=Chip Resistor, 0603, 2-Leads, Body 1.57x0.85mm, IPC Medium Density|UseComponentLibrary=T|ModelName=RESC1608X50N|ModelType=PCBLIB|DatafileCount=1|ModelDatafileEntity0=RESC1608X50N|ModelDatafileKind0=PCBLib|IsCurrent=T|DatalinksLocked=T|DatabaseDatalinksLocked=T|IntegratedModel=T|DatabaseModel=T
|RECORD=46|OwnerIndex=398
|RECORD=48|OwnerIndex=398
|RECORD=1|LibReference=RES_0603_10K|ComponentDescription=RES, 10K, 1%, 1/10W, TF, 0603|PartCount=2|DisplayModeCount=1|IndexInSheet=26|OwnerPartId=-1|Location.X=860|Location.Y=760|Orientation=1|CurrentPartId=1|LibraryPath=*|SourceLibraryName=Resistors.IntLib|TargetFileName=*|AreaColor=11599871|Color=128|PartIDLocked=F|DesignItemId=RES_0603_10K|AllPinCount=2
|RECORD=41|OwnerIndex=401|OwnerPartId=-1|Location.X=856|Location.Y=812|Color=8388608|FontID=6|IsHidden=T|Text=7/25/2013|Name=ModifyDate
|RECORD=41|OwnerIndex=401|IndexInSheet=1|OwnerPartId=-1|Location.X=856|Location.Y=812|Color=8388608|FontID=6|IsHidden=T|Text=ERJ-3EKF1002V|Name=MFG PART NUM
|RECORD=41|OwnerIndex=401|IndexInSheet=2|OwnerPartId=-1|Location.X=856|Location.Y=812|Color=8388608|FontID=6|IsHidden=T|Text=PANASONIC|Name=MFG NAME
|RECORD=41|OwnerIndex=401|IndexInSheet=3|OwnerPartId=-1|Location.X=856|Location.Y=812|Color=8388608|FontID=6|IsHidden=T|Text=RES|Name=CATEGORY
|RECORD=41|OwnerIndex=401|IndexInSheet=4|OwnerPartId=-1|Location.X=856|Location.Y=812|Color=8388608|FontID=6|IsHidden=T|Text=7/26/2013|Name=Date
|RECORD=41|OwnerIndex=401|IndexInSheet=5|OwnerPartId=-1|Location.X=856|Location.Y=812|Color=8388608|FontID=6|IsHidden=T|Text=1%|Name=P1
|RECORD=41|OwnerIndex=401|IndexInSheet=6|OwnerPartId=-1|Location.X=856|Location.Y=812|Color=8388608|FontID=6|IsHidden=T|Text=TF|Name=P3
|RECORD=41|OwnerIndex=401|IndexInSheet=7|OwnerPartId=-1|Location.X=856|Location.Y=812|Color=8388608|FontID=6|IsHidden=T|Text=1/10W|Name=P2
|RECORD=41|OwnerIndex=401|IndexInSheet=8|OwnerPartId=-1|Location.X=856|Location.Y=812|Color=8388608|FontID=6|IsHidden=T|Text=125C|Name=MAXTEMP
|RECORD=41|OwnerIndex=401|IndexInSheet=9|OwnerPartId=-1|Location.X=856|Location.Y=812|Color=8388608|FontID=6|IsHidden=T|Text=-55C|Name=MINTEMP
|RECORD=41|OwnerIndex=401|IndexInSheet=10|OwnerPartId=-1|Location.X=856|Location.Y=812|Color=8388608|FontID=6|IsHidden=T|Text=100PPM|Name=OTHER
|RECORD=41|OwnerIndex=401|IndexInSheet=11|OwnerPartId=-1|Location.X=856|Location.Y=812|Color=8388608|FontID=6|IsHidden=T|Text=0603|Name=SIZE
|RECORD=41|OwnerIndex=401|IndexInSheet=12|OwnerPartId=-1|Location.X=856|Location.Y=812|Color=8388608|FontID=6|IsHidden=T|Text=GENERIC|Name=SUB
|RECORD=41|OwnerIndex=401|IndexInSheet=13|OwnerPartId=-1|Location.X=856|Location.Y=812|Color=8388608|FontID=6|IsHidden=T|Text=Digi-Key|Name=Supplier 1|ReadOnlyState=3
|RECORD=41|OwnerIndex=401|IndexInSheet=14|OwnerPartId=-1|Location.X=856|Location.Y=812|Color=8388608|FontID=6|IsHidden=T|Text=P10.0KHCT-ND|Name=Supplier Part Number 1|ReadOnlyState=3
|RECORD=41|OwnerIndex=401|IndexInSheet=15|OwnerPartId=-1|Location.X=856|Location.Y=812|Color=8388608|FontID=1|IsHidden=T|Text=*|Name=SHEETPART
|RECORD=41|OwnerIndex=401|IndexInSheet=16|OwnerPartId=-1|Location.X=856|Location.Y=812|Color=8388608|FontID=1|IsHidden=T|Text=RES, 10K, 1%, 1/10W, TF, 0603|Name=DESC
|RECORD=41|OwnerIndex=401|IndexInSheet=17|OwnerPartId=-1|Location.X=864|Location.Y=775|Color=8388608|FontID=6|Text=10K|Name=VALUE
|RECORD=2|OwnerIndex=401|OwnerPartId=1|FormalType=1|Electrical=4|PinConglomerate=35|PinLength=10|Location.X=860|Location.Y=770|Name=1|Designator=1|PinPropagationDelay=0.000000E+000
|RECORD=2|OwnerIndex=401|OwnerPartId=1|FormalType=1|Electrical=4|PinConglomerate=33|PinLength=10|Location.X=860|Location.Y=800|Name=2|Designator=2|PinPropagationDelay=0.000000E+000
|RECORD=6|OwnerIndex=401|IsNotAccesible=T|IndexInSheet=20|OwnerPartId=1|LineWidth=1|Color=16711680|LocationCount=7|X1=860|Y1=800|X2=857|Y2=797|X3=863|Y3=791|X4=857|Y4=785|X5=863|Y5=779|X6=857|Y6=773|X7=860|Y7=770
|RECORD=41|OwnerIndex=401|IndexInSheet=21|OwnerPartId=-1|Location.X=856|Location.Y=812|Color=8388608|FontID=1|IsHidden=T|Text=<VELENTIUM>|Name=VELENTIUM PART NUM
|RECORD=34|OwnerIndex=401|IndexInSheet=-1|OwnerPartId=-1|Location.X=864|Location.Y=787|Color=8388608|FontID=1|Text=R6|Name=Designator|ReadOnlyState=1
|RECORD=41|OwnerIndex=401|IndexInSheet=-1|OwnerPartId=-1|Location.X=856|Location.Y=812|Color=8388608|FontID=1|IsHidden=T|Text==MFG PART NUM|Name=Comment
|RECORD=44|OwnerIndex=401
|RECORD=45|OwnerIndex=428|IndexInSheet=-1|Description=Chip Resistor, 0603, 2-Leads, Body 1.57x0.85mm, IPC Medium Density|UseComponentLibrary=T|ModelName=RESC1608X50N|ModelType=PCBLIB|DatafileCount=1|ModelDatafileEntity0=RESC1608X50N|ModelDatafileKind0=PCBLib|IsCurrent=T|DatalinksLocked=T|DatabaseDatalinksLocked=T|IntegratedModel=T|DatabaseModel=T
|RECORD=46|OwnerIndex=429
|RECORD=48|OwnerIndex=429
|RECORD=1|LibReference=RES_0603_47K|ComponentDescription=RES, 47K, 1%, 1/10W, TF, 0603|PartCount=2|DisplayModeCount=1|IndexInSheet=27|OwnerPartId=-1|Location.X=920|Location.Y=840|Orientation=2|CurrentPartId=1|LibraryPath=*|SourceLibraryName=Resistors.IntLib|TargetFileName=*|AreaColor=11599871|Color=128|PartIDLocked=F|DesignItemId=RES_0603_47K|AllPinCount=2
|RECORD=41|OwnerIndex=432|OwnerPartId=-1|Location.X=868|Location.Y=844|Color=8388608|FontID=6|IsHidden=T|Text=1/22/2014|Name=ModifyDate
|RECORD=41|OwnerIndex=432|IndexInSheet=1|OwnerPartId=-1|Location.X=868|Location.Y=844|Color=8388608|FontID=6|IsHidden=T|Text=ERJ-3EKF4702V|Name=MFG PART NUM
|RECORD=41|OwnerIndex=432|IndexInSheet=2|OwnerPartId=-1|Location.X=868|Location.Y=844|Color=8388608|FontID=6|IsHidden=T|Text=PANASONIC|Name=MFG NAME
|RECORD=41|OwnerIndex=432|IndexInSheet=3|OwnerPartId=-1|Location.X=868|Location.Y=844|Color=8388608|FontID=6|IsHidden=T|Text=RES|Name=CATEGORY
|RECORD=41|OwnerIndex=432|IndexInSheet=4|OwnerPartId=-1|Location.X=868|Location.Y=844|Color=8388608|FontID=6|IsHidden=T|Text=1/22/2014|Name=Date
|RECORD=41|OwnerIndex=432|IndexInSheet=5|OwnerPartId=-1|Location.X=868|Location.Y=844|Color=8388608|FontID=6|IsHidden=T|Text=1%|Name=P1
|RECORD=41|OwnerIndex=432|IndexInSheet=6|OwnerPartId=-1|Location.X=868|Location.Y=844|Color=8388608|FontID=6|IsHidden=T|Text=TF|Name=P3
|RECORD=41|OwnerIndex=432|IndexInSheet=7|OwnerPartId=-1|Location.X=868|Location.Y=844|Color=8388608|FontID=6|IsHidden=T|Text=1/10W|Name=P2
|RECORD=41|OwnerIndex=432|IndexInSheet=8|OwnerPartId=-1|Location.X=868|Location.Y=844|Color=8388608|FontID=6|IsHidden=T|Text=125C|Name=MAXTEMP
|RECORD=41|OwnerIndex=432|IndexInSheet=9|OwnerPartId=-1|Location.X=868|Location.Y=844|Color=8388608|FontID=6|IsHidden=T|Text=-55C|Name=MINTEMP
|RECORD=41|OwnerIndex=432|IndexInSheet=10|OwnerPartId=-1|Location.X=868|Location.Y=844|Color=8388608|FontID=6|IsHidden=T|Text=100PPM|Name=OTHER
|RECORD=41|OwnerIndex=432|IndexInSheet=11|OwnerPartId=-1|Location.X=868|Location.Y=844|Color=8388608|FontID=6|IsHidden=T|Text=0603|Name=SIZE
|RECORD=41|OwnerIndex=432|IndexInSheet=12|OwnerPartId=-1|Location.X=868|Location.Y=844|Color=8388608|FontID=6|IsHidden=T|Text=GENERIC|Name=SUB
|RECORD=41|OwnerIndex=432|IndexInSheet=13|OwnerPartId=-1|Location.X=868|Location.Y=844|Color=8388608|FontID=1|IsHidden=T|Text=*|Name=SHEETPART
|RECORD=41|OwnerIndex=432|IndexInSheet=14|OwnerPartId=-1|Location.X=868|Location.Y=844|Color=8388608|FontID=1|IsHidden=T|Text=RES, 47K, 1%, 1/10W, TF, 0603|Name=DESC
|RECORD=41|OwnerIndex=432|IndexInSheet=15|OwnerPartId=-1|Location.X=868|Location.Y=844|Color=8388608|FontID=1|IsHidden=T|Text=Digi-Key|Name=Supplier 1|ReadOnlyState=3
|RECORD=41|OwnerIndex=432|IndexInSheet=16|OwnerPartId=-1|Location.X=868|Location.Y=844|Color=8388608|FontID=1|IsHidden=T|Text=P47.0KHCT-ND|Name=Supplier Part Number 1|ReadOnlyState=3
|RECORD=41|OwnerIndex=432|IndexInSheet=17|OwnerPartId=-1|Location.X=879|Location.Y=824|Color=8388608|FontID=6|Text=47K|Name=VALUE
|RECORD=2|OwnerIndex=432|OwnerPartId=1|FormalType=1|Electrical=4|PinConglomerate=32|PinLength=10|Location.X=910|Location.Y=840|Name=1|Designator=1|PinPropagationDelay=0.000000E+000
|RECORD=2|OwnerIndex=432|OwnerPartId=1|FormalType=1|Electrical=4|PinConglomerate=34|PinLength=10|Location.X=880|Location.Y=840|Name=2|Designator=2|PinPropagationDelay=0.000000E+000
|RECORD=6|OwnerIndex=432|IsNotAccesible=T|IndexInSheet=20|OwnerPartId=1|LineWidth=1|Color=16711680|LocationCount=7|X1=880|Y1=840|X2=883|Y2=837|X3=889|Y3=843|X4=895|Y4=837|X5=901|Y5=843|X6=907|Y6=837|X7=910|Y7=840
|RECORD=41|OwnerIndex=432|IndexInSheet=21|OwnerPartId=-1|Location.X=868|Location.Y=844|Color=8388608|FontID=1|IsHidden=T|Text=<VELENTIUM>|Name=VELENTIUM PART NUM
|RECORD=34|OwnerIndex=432|IndexInSheet=-1|OwnerPartId=-1|Location.X=879|Location.Y=844|Color=8388608|FontID=1|Text=R4|Name=Designator|ReadOnlyState=1
|RECORD=41|OwnerIndex=432|IndexInSheet=-1|OwnerPartId=-1|Location.X=868|Location.Y=844|Color=8388608|FontID=1|IsHidden=T|Text==MFG PART NUM|Name=Comment
|RECORD=44|OwnerIndex=432
|RECORD=45|OwnerIndex=459|IndexInSheet=-1|Description=Chip Resistor, 0603, 2-Leads, Body 1.57x0.85mm, IPC Medium Density|UseComponentLibrary=T|ModelName=RESC1608X50N|ModelType=PCBLIB|DatafileCount=1|ModelDatafileEntity0=RESC1608X50N|ModelDatafileKind0=PCBLib|IsCurrent=T|DatalinksLocked=T|DatabaseDatalinksLocked=T|IntegratedModel=T|DatabaseModel=T
|RECORD=46|OwnerIndex=460
|RECORD=48|OwnerIndex=460
|RECORD=1|LibReference=CAP_0603_0.01UF_50V|ComponentDescription=CAP, CER, 0.01UF, 50V, 10%, X7R, 0603|PartCount=2|DisplayModeCount=1|IndexInSheet=28|OwnerPartId=-1|Location.X=850|Location.Y=940|Orientation=1|CurrentPartId=1|LibraryPath=*|SourceLibraryName=Capacitors.IntLib|TargetFileName=*|AreaColor=11599871|Color=128|PartIDLocked=F|DesignItemId=CAP_0603_0.01UF_50V|AllPinCount=2
|RECORD=41|OwnerIndex=463|OwnerPartId=-1|Location.X=798|Location.Y=966|Color=8388608|FontID=6|IsHidden=T|Text=CAP, CER|Name=CATEGORY
|RECORD=41|OwnerIndex=463|IndexInSheet=1|OwnerPartId=-1|Location.X=798|Location.Y=966|Color=8388608|FontID=6|IsHidden=T|Text=KEMET|Name=MFG NAME
|RECORD=41|OwnerIndex=463|IndexInSheet=2|OwnerPartId=-1|Location.X=798|Location.Y=966|Color=8388608|FontID=6|IsHidden=T|Text=C0603C103K5RACTU|Name=MFG PART NUM
|RECORD=41|OwnerIndex=463|IndexInSheet=3|OwnerPartId=-1|Location.X=798|Location.Y=966|Color=8388608|FontID=6|IsHidden=T|Text=10/23/2013|Name=MODIFY DATE
|RECORD=41|OwnerIndex=463|IndexInSheet=4|OwnerPartId=-1|Location.X=798|Location.Y=966|Color=8388608|FontID=6|IsHidden=T|Text=7/24/2013|Name=Date
|RECORD=41|OwnerIndex=463|IndexInSheet=5|OwnerPartId=-1|Location.X=798|Location.Y=966|Color=8388608|FontID=6|IsHidden=T|Text=*|Name=SHEETPART
|RECORD=41|OwnerIndex=463|IndexInSheet=6|OwnerPartId=-1|Location.X=798|Location.Y=966|Color=8388608|FontID=6|IsHidden=T|Text=10%|Name=P1
|RECORD=41|OwnerIndex=463|IndexInSheet=7|OwnerPartId=-1|Location.X=798|Location.Y=966|Color=8388608|FontID=6|IsHidden=T|Text=125C|Name=MAXTEMP
|RECORD=41|OwnerIndex=463|IndexInSheet=8|OwnerPartId=-1|Location.X=798|Location.Y=966|Color=8388608|FontID=6|IsHidden=T|Text=-55C|Name=MINTEMP
|RECORD=41|OwnerIndex=463|IndexInSheet=9|OwnerPartId=-1|Location.X=798|Location.Y=966|Color=8388608|FontID=6|IsHidden=T|Name=OTHER
|RECORD=41|OwnerIndex=463|IndexInSheet=10|OwnerPartId=-1|Location.X=798|Location.Y=966|Color=8388608|FontID=6|IsHidden=T|Text=50V|Name=P2
|RECORD=41|OwnerIndex=463|IndexInSheet=11|OwnerPartId=-1|Location.X=798|Location.Y=966|Color=8388608|FontID=6|IsHidden=T|Text=X7R|Name=P3
|RECORD=41|OwnerIndex=463|IndexInSheet=12|OwnerPartId=-1|Location.X=798|Location.Y=966|Color=8388608|FontID=6|IsHidden=T|Text=0603|Name=Size
|RECORD=41|OwnerIndex=463|IndexInSheet=13|OwnerPartId=-1|Location.X=798|Location.Y=966|Color=8388608|FontID=6|IsHidden=T|Name=SUB
|RECORD=41|OwnerIndex=463|IndexInSheet=14|OwnerPartId=-1|Location.X=798|Location.Y=966|Color=8388608|FontID=6|IsHidden=T|Text=Digi-Key|Name=Supplier 1|ReadOnlyState=3
|RECORD=41|OwnerIndex=463|IndexInSheet=15|OwnerPartId=-1|Location.X=798|Location.Y=966|Color=8388608|FontID=6|IsHidden=T|Text=399-1091-1-ND|Name=Supplier Part Number 1|ReadOnlyState=3
|RECORD=41|OwnerIndex=463|IndexInSheet=16|OwnerPartId=-1|Location.X=798|Location.Y=966|Color=8388608|FontID=1|IsHidden=T|Text=CAP, CER, 0.01UF, 50V, 10%, X7R, 0603|Name=DESC
|RECORD=41|OwnerIndex=463|IndexInSheet=17|OwnerPartId=-1|Location.X=809|Location.Y=942|Color=8388608|FontID=6|Text=0.01uF|Name=VALUE
|RECORD=2|OwnerIndex=463|OwnerPartId=1|FormalType=1|Electrical=4|PinConglomerate=32|PinLength=10|Location.X=820|Location.Y=960|Name=2|Designator=2|SwapIdPin=2|SwapIDPart=1|PinPropagationDelay=0.000000E+000
|RECORD=2|OwnerIndex=463|OwnerPartId=1|FormalType=1|Electrical=4|PinConglomerate=34|PinLength=10|Location.X=810|Location.Y=960|Name=1|Designator=1|SwapIdPin=1|SwapIDPart=1|PinPropagationDelay=0.000000E+000
|RECORD=13|OwnerIndex=463|IsNotAccesible=T|IndexInSheet=20|OwnerPartId=1|Location.X=817|Location.X_Frac=50000|Location.Y=960|Corner.X=820|Corner.Y=960|LineWidth=1|Color=16711680
|RECORD=13|OwnerIndex=463|IsNotAccesible=T|IndexInSheet=21|OwnerPartId=1|Location.X=810|Location.Y=960|Corner.X=812|Corner.X_Frac=50000|Corner.Y=960|LineWidth=1|Color=16711680
|RECORD=13|OwnerIndex=463|IsNotAccesible=T|IndexInSheet=22|OwnerPartId=1|Location.X=817|Location.X_Frac=50000|Location.Y=965|Corner.X=817|Corner.X_Frac=50000|Corner.Y=955|LineWidth=1|Color=16711680
|RECORD=13|OwnerIndex=463|IsNotAccesible=T|IndexInSheet=23|OwnerPartId=1|Location.X=812|Location.X_Frac=50000|Location.Y=965|Corner.X=812|Corner.X_Frac=50000|Corner.Y=955|LineWidth=1|Color=16711680
|RECORD=41|OwnerIndex=463|IndexInSheet=24|OwnerPartId=-1|Location.X=798|Location.Y=966|Color=8388608|FontID=1|IsHidden=T|Text=<VALENTIUM>|Name=VALENTIUM PART NUM
|RECORD=34|OwnerIndex=463|IndexInSheet=-1|OwnerPartId=-1|Location.X=809|Location.Y=966|Color=8388608|FontID=1|Text=C4|Name=Designator|ReadOnlyState=1
|RECORD=41|OwnerIndex=463|IndexInSheet=-1|OwnerPartId=-1|Location.X=798|Location.Y=966|Color=8388608|FontID=1|IsHidden=T|Text=CAP_0603_0.01UF_50V|Name=Comment|ReadOnlyState=1
|RECORD=44|OwnerIndex=463
|RECORD=45|OwnerIndex=493|IndexInSheet=-1|Description=Chip Capacitor, 0603, 2-Leads, Body 1.60x0.80mm, IPC Medium Density|UseComponentLibrary=T|ModelName=CAPC1608X10N|ModelType=PCBLIB|DatafileCount=1|ModelDatafileEntity0=CAPC1608X10N|ModelDatafileKind0=PCBLib|IsCurrent=T|DatalinksLocked=T|DatabaseDatalinksLocked=T|IntegratedModel=T|DatabaseModel=T
|RECORD=46|OwnerIndex=494
|RECORD=48|OwnerIndex=494
|RECORD=1|LibReference=PM124SH-100M-RC|ComponentDescription=IND, PWR, 10.uH, 20%, 4A, 0.04DCR, 12.5X12.5MM, SHLD|PartCount=2|DisplayModeCount=1|IndexInSheet=29|OwnerPartId=-1|Location.X=850|Location.Y=870|CurrentPartId=1|LibraryPath=*|SourceLibraryName=Passives.IntLib|TargetFileName=*|AreaColor=11599871|Color=128|PartIDLocked=F|DesignItemId=PM124SH-100M-RC|AllPinCount=2
|RECORD=41|OwnerIndex=497|OwnerPartId=-1|Location.X=850|Location.Y=870|Color=8388608|FontID=6|IsHidden=T|Text=PM124SH-100M-RC|Name=MFG PART NUM
|RECORD=41|OwnerIndex=497|IndexInSheet=1|OwnerPartId=-1|Location.X=850|Location.Y=870|Color=8388608|FontID=6|IsHidden=T|Text=10/23/2013|Name=MODIFY DATE
|RECORD=41|OwnerIndex=497|IndexInSheet=2|OwnerPartId=-1|Location.X=850|Location.Y=870|Color=8388608|FontID=6|IsHidden=T|Text=BOURNS|Name=MFG NAME
|RECORD=41|OwnerIndex=497|IndexInSheet=3|OwnerPartId=-1|Location.X=848|Location.Y=892|Location.Y_Frac=10000|Color=8388608|FontID=6|IsHidden=T|Text=10/23/2013|Name=Date
|RECORD=41|OwnerIndex=497|IndexInSheet=4|OwnerPartId=-1|Location.X=848|Location.Y=892|Location.Y_Frac=10000|Color=8388608|FontID=6|IsHidden=T|Text=IND, PWR|Name=CATEGORY
|RECORD=41|OwnerIndex=497|IndexInSheet=5|OwnerPartId=-1|Location.X=848|Location.Y=898|Color=8388608|FontID=6|IsHidden=T|Text=125C|Name=MAXTEMP
|RECORD=41|OwnerIndex=497|IndexInSheet=6|OwnerPartId=-1|Location.X=848|Location.Y=898|Color=8388608|FontID=6|IsHidden=T|Text=-40C|Name=MINTEMP
|RECORD=41|OwnerIndex=497|IndexInSheet=7|OwnerPartId=-1|Location.X=848|Location.Y=898|Color=8388608|FontID=6|IsHidden=T|Text=SHLD|Name=OTHER
|RECORD=41|OwnerIndex=497|IndexInSheet=8|OwnerPartId=-1|Location.X=848|Location.Y=898|Color=8388608|FontID=6|IsHidden=T|Text=20%|Name=P1
|RECORD=41|OwnerIndex=497|IndexInSheet=9|OwnerPartId=-1|Location.X=848|Location.Y=898|Color=8388608|FontID=6|IsHidden=T|Text=4A|Name=P2
|RECORD=41|OwnerIndex=497|IndexInSheet=10|OwnerPartId=-1|Location.X=848|Location.Y=898|Color=8388608|FontID=6|IsHidden=T|Text=36mOhm|Name=P3
|RECORD=41|OwnerIndex=497|IndexInSheet=11|OwnerPartId=-1|Location.X=848|Location.Y=898|Color=8388608|FontID=6|IsHidden=T|Text=12.5X12.5MM|Name=SIZE
|RECORD=41|OwnerIndex=497|IndexInSheet=12|OwnerPartId=-1|Location.X=848|Location.Y=898|Color=8388608|FontID=6|IsHidden=T|Name=SUB
|RECORD=41|OwnerIndex=497|IndexInSheet=13|OwnerPartId=-1|Location.X=848|Location.Y=857|Color=8388608|FontID=1|IsHidden=T|Text=*|Name=SHEETPART
|RECORD=41|OwnerIndex=497|IndexInSheet=14|OwnerPartId=-1|Location.X=848|Location.Y=902|Color=8388608|FontID=1|IsHidden=T|Text=IND, PWR, 10.uH, 20%, 4A, 0.04DCR, 12.5X12.5MM, SHLD|Name=DESC
|RECORD=41|OwnerIndex=497|IndexInSheet=15|OwnerPartId=-1|Location.X=848|Location.Y=902|Color=8388608|FontID=1|IsHidden=T|Text=Digi-Key|Name=Supplier 1|ReadOnlyState=3
|RECORD=41|OwnerIndex=497|IndexInSheet=16|OwnerPartId=-1|Location.X=848|Location.Y=902|Color=8388608|FontID=1|IsHidden=T|Text=PM124SH-100M-RCCT-ND|Name=Supplier Part Number 1|ReadOnlyState=3
|RECORD=2|OwnerIndex=497|OwnerPartId=1|FormalType=1|Electrical=4|PinConglomerate=32|PinLength=20|Location.X=910|Location.Y=870|Designator=1|PinPropagationDelay=0.000000E+000
|RECORD=2|OwnerIndex=497|OwnerPartId=1|FormalType=1|Electrical=4|PinConglomerate=34|PinLength=20|Location.X=870|Location.Y=870|Designator=2|PinPropagationDelay=0.000000E+000
|RECORD=12|OwnerIndex=497|IsNotAccesible=T|IndexInSheet=19|OwnerPartId=1|Location.X=905|Location.Y=875|Radius=5|LineWidth=1|EndAngle=180.000|Color=16711680
|RECORD=12|OwnerIndex=497|IsNotAccesible=T|IndexInSheet=20|OwnerPartId=1|Location.X=895|Location.Y=875|Radius=5|LineWidth=1|EndAngle=180.000|Color=16711680
|RECORD=12|OwnerIndex=497|IsNotAccesible=T|IndexInSheet=21|OwnerPartId=1|Location.X=885|Location.Y=875|Radius=5|LineWidth=1|EndAngle=180.000|Color=16711680
|RECORD=12|OwnerIndex=497|IsNotAccesible=T|IndexInSheet=22|OwnerPartId=1|Location.X=875|Location.Y=875|Radius=5|LineWidth=1|EndAngle=180.000|Color=16711680
|RECORD=13|OwnerIndex=497|IsNotAccesible=T|IndexInSheet=23|OwnerPartId=1|Location.X=910|Location.Y=875|Corner.X=910|Corner.Y=870|LineWidth=1|Color=16711680
|RECORD=13|OwnerIndex=497|IsNotAccesible=T|IndexInSheet=24|OwnerPartId=1|Location.X=900|Location.Y=875|Corner.X=900|Corner.Y=870|LineWidth=1|Color=16711680
|RECORD=13|OwnerIndex=497|IsNotAccesible=T|IndexInSheet=25|OwnerPartId=1|Location.X=890|Location.Y=875|Corner.X=890|Corner.Y=870|LineWidth=1|Color=16711680
|RECORD=13|OwnerIndex=497|IsNotAccesible=T|IndexInSheet=26|OwnerPartId=1|Location.X=880|Location.Y=875|Corner.X=880|Corner.Y=870|LineWidth=1|Color=16711680
|RECORD=13|OwnerIndex=497|IsNotAccesible=T|IndexInSheet=27|OwnerPartId=1|Location.X=870|Location.Y=875|Corner.X=870|Corner.Y=870|LineWidth=1|Color=16711680
|RECORD=41|OwnerIndex=497|IndexInSheet=28|OwnerPartId=-1|Location.X=869|Location.Y=855|Color=8388608|FontID=6|Text=10.uH|Name=VALUE
|RECORD=41|OwnerIndex=497|IndexInSheet=29|OwnerPartId=-1|Location.X=848|Location.Y=902|Color=8388608|FontID=1|IsHidden=T|Text=<VALENTIUM>|Name=VALENTIUM PART NUM
|RECORD=34|OwnerIndex=497|IndexInSheet=-1|OwnerPartId=-1|Location.X=869|Location.Y=880|Color=8388608|FontID=1|Text=L1|Name=Designator|ReadOnlyState=1
|RECORD=41|OwnerIndex=497|IndexInSheet=-1|OwnerPartId=-1|Location.X=850|Location.Y=870|Color=8388608|FontID=1|IsHidden=T|Text=PM124SH-100M-RC|Name=Comment
|RECORD=44|OwnerIndex=497
|RECORD=45|OwnerIndex=532|IndexInSheet=-1|Description=Footprint not found|UseComponentLibrary=T|ModelName=IND_PM124SH|ModelType=PCBLIB|DatafileCount=1|ModelDatafileEntity0=IND_PM124SH|ModelDatafileKind0=PCBLib|IsCurrent=T|DatalinksLocked=T|DatabaseDatalinksLocked=T|IntegratedModel=T|DatabaseModel=T
|RECORD=46|OwnerIndex=533
|RECORD=48|OwnerIndex=533
|RECORD=1|LibReference=PM124SH-100M-RC|ComponentDescription=IND, PWR, 10.uH, 20%, 4A, 0.04DCR, 12.5X12.5MM, SHLD|PartCount=2|DisplayModeCount=1|IndexInSheet=30|OwnerPartId=-1|Location.X=850|Location.Y=460|CurrentPartId=1|LibraryPath=*|SourceLibraryName=Passives.IntLib|TargetFileName=*|AreaColor=11599871|Color=128|PartIDLocked=F|DesignItemId=PM124SH-100M-RC|AllPinCount=2
|RECORD=41|OwnerIndex=536|OwnerPartId=-1|Location.X=850|Location.Y=460|Color=8388608|FontID=6|IsHidden=T|Text=PM124SH-100M-RC|Name=MFG PART NUM
|RECORD=41|OwnerIndex=536|IndexInSheet=1|OwnerPartId=-1|Location.X=850|Location.Y=460|Color=8388608|FontID=6|IsHidden=T|Text=10/23/2013|Name=MODIFY DATE
|RECORD=41|OwnerIndex=536|IndexInSheet=2|OwnerPartId=-1|Location.X=850|Location.Y=460|Color=8388608|FontID=6|IsHidden=T|Text=BOURNS|Name=MFG NAME
|RECORD=41|OwnerIndex=536|IndexInSheet=3|OwnerPartId=-1|Location.X=848|Location.Y=482|Location.Y_Frac=10000|Color=8388608|FontID=6|IsHidden=T|Text=10/23/2013|Name=Date
|RECORD=41|OwnerIndex=536|IndexInSheet=4|OwnerPartId=-1|Location.X=848|Location.Y=482|Location.Y_Frac=10000|Color=8388608|FontID=6|IsHidden=T|Text=IND, PWR|Name=CATEGORY
|RECORD=41|OwnerIndex=536|IndexInSheet=5|OwnerPartId=-1|Location.X=848|Location.Y=488|Color=8388608|FontID=6|IsHidden=T|Text=125C|Name=MAXTEMP
|RECORD=41|OwnerIndex=536|IndexInSheet=6|OwnerPartId=-1|Location.X=848|Location.Y=488|Color=8388608|FontID=6|IsHidden=T|Text=-40C|Name=MINTEMP
|RECORD=41|OwnerIndex=536|IndexInSheet=7|OwnerPartId=-1|Location.X=848|Location.Y=488|Color=8388608|FontID=6|IsHidden=T|Text=SHLD|Name=OTHER
|RECORD=41|OwnerIndex=536|IndexInSheet=8|OwnerPartId=-1|Location.X=848|Location.Y=488|Color=8388608|FontID=6|IsHidden=T|Text=20%|Name=P1
|RECORD=41|OwnerIndex=536|IndexInSheet=9|OwnerPartId=-1|Location.X=848|Location.Y=488|Color=8388608|FontID=6|IsHidden=T|Text=4A|Name=P2
|RECORD=41|OwnerIndex=536|IndexInSheet=10|OwnerPartId=-1|Location.X=848|Location.Y=488|Color=8388608|FontID=6|IsHidden=T|Text=36mOhm|Name=P3
|RECORD=41|OwnerIndex=536|IndexInSheet=11|OwnerPartId=-1|Location.X=848|Location.Y=488|Color=8388608|FontID=6|IsHidden=T|Text=12.5X12.5MM|Name=SIZE
|RECORD=41|OwnerIndex=536|IndexInSheet=12|OwnerPartId=-1|Location.X=848|Location.Y=488|Color=8388608|FontID=6|IsHidden=T|Name=SUB
|RECORD=41|OwnerIndex=536|IndexInSheet=13|OwnerPartId=-1|Location.X=848|Location.Y=447|Color=8388608|FontID=1|IsHidden=T|Text=*|Name=SHEETPART
|RECORD=41|OwnerIndex=536|IndexInSheet=14|OwnerPartId=-1|Location.X=848|Location.Y=492|Color=8388608|FontID=1|IsHidden=T|Text=IND, PWR, 10.uH, 20%, 4A, 0.04DCR, 12.5X12.5MM, SHLD|Name=DESC
|RECORD=41|OwnerIndex=536|IndexInSheet=15|OwnerPartId=-1|Location.X=848|Location.Y=492|Color=8388608|FontID=1|IsHidden=T|Text=Digi-Key|Name=Supplier 1|ReadOnlyState=3
|RECORD=41|OwnerIndex=536|IndexInSheet=16|OwnerPartId=-1|Location.X=848|Location.Y=492|Color=8388608|FontID=1|IsHidden=T|Text=PM124SH-100M-RCCT-ND|Name=Supplier Part Number 1|ReadOnlyState=3
|RECORD=2|OwnerIndex=536|OwnerPartId=1|FormalType=1|Electrical=4|PinConglomerate=32|PinLength=20|Location.X=910|Location.Y=460|Designator=1|PinPropagationDelay=0.000000E+000
|RECORD=2|OwnerIndex=536|OwnerPartId=1|FormalType=1|Electrical=4|PinConglomerate=34|PinLength=20|Location.X=870|Location.Y=460|Designator=2|PinPropagationDelay=0.000000E+000
|RECORD=12|OwnerIndex=536|IsNotAccesible=T|IndexInSheet=19|OwnerPartId=1|Location.X=905|Location.Y=465|Radius=5|LineWidth=1|EndAngle=180.000|Color=16711680
|RECORD=12|OwnerIndex=536|IsNotAccesible=T|IndexInSheet=20|OwnerPartId=1|Location.X=895|Location.Y=465|Radius=5|LineWidth=1|EndAngle=180.000|Color=16711680
|RECORD=12|OwnerIndex=536|IsNotAccesible=T|IndexInSheet=21|OwnerPartId=1|Location.X=885|Location.Y=465|Radius=5|LineWidth=1|EndAngle=180.000|Color=16711680
|RECORD=12|OwnerIndex=536|IsNotAccesible=T|IndexInSheet=22|OwnerPartId=1|Location.X=875|Location.Y=465|Radius=5|LineWidth=1|EndAngle=180.000|Color=16711680
|RECORD=13|OwnerIndex=536|IsNotAccesible=T|IndexInSheet=23|OwnerPartId=1|Location.X=910|Location.Y=465|Corner.X=910|Corner.Y=460|LineWidth=1|Color=16711680
|RECORD=13|OwnerIndex=536|IsNotAccesible=T|IndexInSheet=24|OwnerPartId=1|Location.X=900|Location.Y=465|Corner.X=900|Corner.Y=460|LineWidth=1|Color=16711680
|RECORD=13|OwnerIndex=536|IsNotAccesible=T|IndexInSheet=25|OwnerPartId=1|Location.X=890|Location.Y=465|Corner.X=890|Corner.Y=460|LineWidth=1|Color=16711680
|RECORD=13|OwnerIndex=536|IsNotAccesible=T|IndexInSheet=26|OwnerPartId=1|Location.X=880|Location.Y=465|Corner.X=880|Corner.Y=460|LineWidth=1|Color=16711680
|RECORD=13|OwnerIndex=536|IsNotAccesible=T|IndexInSheet=27|OwnerPartId=1|Location.X=870|Location.Y=465|Corner.X=870|Corner.Y=460|LineWidth=1|Color=16711680
|RECORD=41|OwnerIndex=536|IndexInSheet=28|OwnerPartId=-1|Location.X=869|Location.Y=445|Color=8388608|FontID=6|Text=10.uH|Name=VALUE
|RECORD=41|OwnerIndex=536|IndexInSheet=29|OwnerPartId=-1|Location.X=848|Location.Y=492|Color=8388608|FontID=1|IsHidden=T|Text=<VALENTIUM>|Name=VALENTIUM PART NUM
|RECORD=34|OwnerIndex=536|IndexInSheet=-1|OwnerPartId=-1|Location.X=869|Location.Y=470|Color=8388608|FontID=1|Text=L2|Name=Designator|ReadOnlyState=1
|RECORD=41|OwnerIndex=536|IndexInSheet=-1|OwnerPartId=-1|Location.X=850|Location.Y=460|Color=8388608|FontID=1|IsHidden=T|Text=PM124SH-100M-RC|Name=Comment
|RECORD=44|OwnerIndex=536
|RECORD=45|OwnerIndex=571|IndexInSheet=-1|Description=Footprint not found|UseComponentLibrary=T|ModelName=IND_PM124SH|ModelType=PCBLIB|DatafileCount=1|ModelDatafileEntity0=IND_PM124SH|ModelDatafileKind0=PCBLib|IsCurrent=T|DatalinksLocked=T|DatabaseDatalinksLocked=T|IntegratedModel=T|DatabaseModel=T
|RECORD=46|OwnerIndex=572
|RECORD=48|OwnerIndex=572
|RECORD=1|LibReference=CAP_0603_0.01UF_50V|ComponentDescription=CAP, CER, 0.01UF, 50V, 10%, X7R, 0603|PartCount=2|DisplayModeCount=1|IndexInSheet=31|OwnerPartId=-1|Location.X=800|Location.Y=540|Orientation=1|CurrentPartId=1|LibraryPath=*|SourceLibraryName=Capacitors.IntLib|TargetFileName=*|AreaColor=11599871|Color=128|PartIDLocked=F|DesignItemId=CAP_0603_0.01UF_50V|AllPinCount=2
|RECORD=41|OwnerIndex=575|OwnerPartId=-1|Location.X=748|Location.Y=566|Color=8388608|FontID=6|IsHidden=T|Text=CAP, CER|Name=CATEGORY
|RECORD=41|OwnerIndex=575|IndexInSheet=1|OwnerPartId=-1|Location.X=748|Location.Y=566|Color=8388608|FontID=6|IsHidden=T|Text=KEMET|Name=MFG NAME
|RECORD=41|OwnerIndex=575|IndexInSheet=2|OwnerPartId=-1|Location.X=748|Location.Y=566|Color=8388608|FontID=6|IsHidden=T|Text=C0603C103K5RACTU|Name=MFG PART NUM
|RECORD=41|OwnerIndex=575|IndexInSheet=3|OwnerPartId=-1|Location.X=748|Location.Y=566|Color=8388608|FontID=6|IsHidden=T|Text=10/23/2013|Name=MODIFY DATE
|RECORD=41|OwnerIndex=575|IndexInSheet=4|OwnerPartId=-1|Location.X=748|Location.Y=566|Color=8388608|FontID=6|IsHidden=T|Text=7/24/2013|Name=Date
|RECORD=41|OwnerIndex=575|IndexInSheet=5|OwnerPartId=-1|Location.X=748|Location.Y=566|Color=8388608|FontID=6|IsHidden=T|Text=*|Name=SHEETPART
|RECORD=41|OwnerIndex=575|IndexInSheet=6|OwnerPartId=-1|Location.X=748|Location.Y=566|Color=8388608|FontID=6|IsHidden=T|Text=10%|Name=P1
|RECORD=41|OwnerIndex=575|IndexInSheet=7|OwnerPartId=-1|Location.X=748|Location.Y=566|Color=8388608|FontID=6|IsHidden=T|Text=125C|Name=MAXTEMP
|RECORD=41|OwnerIndex=575|IndexInSheet=8|OwnerPartId=-1|Location.X=748|Location.Y=566|Color=8388608|FontID=6|IsHidden=T|Text=-55C|Name=MINTEMP
|RECORD=41|OwnerIndex=575|IndexInSheet=9|OwnerPartId=-1|Location.X=748|Location.Y=566|Color=8388608|FontID=6|IsHidden=T|Name=OTHER
|RECORD=41|OwnerIndex=575|IndexInSheet=10|OwnerPartId=-1|Location.X=748|Location.Y=566|Color=8388608|FontID=6|IsHidden=T|Text=50V|Name=P2
|RECORD=41|OwnerIndex=575|IndexInSheet=11|OwnerPartId=-1|Location.X=748|Location.Y=566|Color=8388608|FontID=6|IsHidden=T|Text=X7R|Name=P3
|RECORD=41|OwnerIndex=575|IndexInSheet=12|OwnerPartId=-1|Location.X=748|Location.Y=566|Color=8388608|FontID=6|IsHidden=T|Text=0603|Name=Size
|RECORD=41|OwnerIndex=575|IndexInSheet=13|OwnerPartId=-1|Location.X=748|Location.Y=566|Color=8388608|FontID=6|IsHidden=T|Name=SUB
|RECORD=41|OwnerIndex=575|IndexInSheet=14|OwnerPartId=-1|Location.X=748|Location.Y=566|Color=8388608|FontID=6|IsHidden=T|Text=Digi-Key|Name=Supplier 1|ReadOnlyState=3
|RECORD=41|OwnerIndex=575|IndexInSheet=15|OwnerPartId=-1|Location.X=748|Location.Y=566|Color=8388608|FontID=6|IsHidden=T|Text=399-1091-1-ND|Name=Supplier Part Number 1|ReadOnlyState=3
|RECORD=41|OwnerIndex=575|IndexInSheet=16|OwnerPartId=-1|Location.X=748|Location.Y=566|Color=8388608|FontID=1|IsHidden=T|Text=CAP, CER, 0.01UF, 50V, 10%, X7R, 0603|Name=DESC
|RECORD=41|OwnerIndex=575|IndexInSheet=17|OwnerPartId=-1|Location.X=759|Location.Y=542|Color=8388608|FontID=6|Text=0.01uF|Name=VALUE
|RECORD=2|OwnerIndex=575|OwnerPartId=1|FormalType=1|Electrical=4|PinConglomerate=32|PinLength=10|Location.X=770|Location.Y=560|Name=2|Designator=2|SwapIdPin=2|SwapIDPart=1|PinPropagationDelay=0.000000E+000
|RECORD=2|OwnerIndex=575|OwnerPartId=1|FormalType=1|Electrical=4|PinConglomerate=34|PinLength=10|Location.X=760|Location.Y=560|Name=1|Designator=1|SwapIdPin=1|SwapIDPart=1|PinPropagationDelay=0.000000E+000
|RECORD=13|OwnerIndex=575|IsNotAccesible=T|IndexInSheet=20|OwnerPartId=1|Location.X=767|Location.X_Frac=50000|Location.Y=560|Corner.X=770|Corner.Y=560|LineWidth=1|Color=16711680
|RECORD=13|OwnerIndex=575|IsNotAccesible=T|IndexInSheet=21|OwnerPartId=1|Location.X=760|Location.Y=560|Corner.X=762|Corner.X_Frac=50000|Corner.Y=560|LineWidth=1|Color=16711680
|RECORD=13|OwnerIndex=575|IsNotAccesible=T|IndexInSheet=22|OwnerPartId=1|Location.X=767|Location.X_Frac=50000|Location.Y=565|Corner.X=767|Corner.X_Frac=50000|Corner.Y=555|LineWidth=1|Color=16711680
|RECORD=13|OwnerIndex=575|IsNotAccesible=T|IndexInSheet=23|OwnerPartId=1|Location.X=762|Location.X_Frac=50000|Location.Y=565|Corner.X=762|Corner.X_Frac=50000|Corner.Y=555|LineWidth=1|Color=16711680
|RECORD=41|OwnerIndex=575|IndexInSheet=24|OwnerPartId=-1|Location.X=748|Location.Y=566|Color=8388608|FontID=1|IsHidden=T|Text=<VALENTIUM>|Name=VALENTIUM PART NUM
|RECORD=34|OwnerIndex=575|IndexInSheet=-1|OwnerPartId=-1|Location.X=759|Location.Y=566|Color=8388608|FontID=1|Text=C3|Name=Designator|ReadOnlyState=1
|RECORD=41|OwnerIndex=575|IndexInSheet=-1|OwnerPartId=-1|Location.X=748|Location.Y=566|Color=8388608|FontID=1|IsHidden=T|Text=CAP_0603_0.01UF_50V|Name=Comment|ReadOnlyState=1
|RECORD=44|OwnerIndex=575
|RECORD=45|OwnerIndex=605|IndexInSheet=-1|Description=Chip Capacitor, 0603, 2-Leads, Body 1.60x0.80mm, IPC Medium Density|UseComponentLibrary=T|ModelName=CAPC1608X10N|ModelType=PCBLIB|DatafileCount=1|ModelDatafileEntity0=CAPC1608X10N|ModelDatafileKind0=PCBLib|IsCurrent=T|DatalinksLocked=T|DatabaseDatalinksLocked=T|IntegratedModel=T|DatabaseModel=T
|RECORD=46|OwnerIndex=606
|RECORD=48|OwnerIndex=606
|RECORD=1|LibReference=RES_0603_47K|ComponentDescription=RES, 47K, 1%, 1/10W, TF, 0603|PartCount=2|DisplayModeCount=1|IndexInSheet=32|OwnerPartId=-1|Location.X=590|Location.Y=490|Orientation=1|CurrentPartId=1|LibraryPath=*|SourceLibraryName=Resistors.IntLib|TargetFileName=*|AreaColor=11599871|Color=128|PartIDLocked=F|DesignItemId=RES_0603_47K|AllPinCount=2
|RECORD=41|OwnerIndex=609|OwnerPartId=-1|Location.X=586|Location.Y=542|Color=8388608|FontID=6|IsHidden=T|Text=1/22/2014|Name=ModifyDate
|RECORD=41|OwnerIndex=609|IndexInSheet=1|OwnerPartId=-1|Location.X=586|Location.Y=542|Color=8388608|FontID=6|IsHidden=T|Text=ERJ-3EKF4702V|Name=MFG PART NUM
|RECORD=41|OwnerIndex=609|IndexInSheet=2|OwnerPartId=-1|Location.X=586|Location.Y=542|Color=8388608|FontID=6|IsHidden=T|Text=PANASONIC|Name=MFG NAME
|RECORD=41|OwnerIndex=609|IndexInSheet=3|OwnerPartId=-1|Location.X=586|Location.Y=542|Color=8388608|FontID=6|IsHidden=T|Text=RES|Name=CATEGORY
|RECORD=41|OwnerIndex=609|IndexInSheet=4|OwnerPartId=-1|Location.X=586|Location.Y=542|Color=8388608|FontID=6|IsHidden=T|Text=1/22/2014|Name=Date
|RECORD=41|OwnerIndex=609|IndexInSheet=5|OwnerPartId=-1|Location.X=586|Location.Y=542|Color=8388608|FontID=6|IsHidden=T|Text=1%|Name=P1
|RECORD=41|OwnerIndex=609|IndexInSheet=6|OwnerPartId=-1|Location.X=586|Location.Y=542|Color=8388608|FontID=6|IsHidden=T|Text=TF|Name=P3
|RECORD=41|OwnerIndex=609|IndexInSheet=7|OwnerPartId=-1|Location.X=586|Location.Y=542|Color=8388608|FontID=6|IsHidden=T|Text=1/10W|Name=P2
|RECORD=41|OwnerIndex=609|IndexInSheet=8|OwnerPartId=-1|Location.X=586|Location.Y=542|Color=8388608|FontID=6|IsHidden=T|Text=125C|Name=MAXTEMP
|RECORD=41|OwnerIndex=609|IndexInSheet=9|OwnerPartId=-1|Location.X=586|Location.Y=542|Color=8388608|FontID=6|IsHidden=T|Text=-55C|Name=MINTEMP
|RECORD=41|OwnerIndex=609|IndexInSheet=10|OwnerPartId=-1|Location.X=586|Location.Y=542|Color=8388608|FontID=6|IsHidden=T|Text=100PPM|Name=OTHER
|RECORD=41|OwnerIndex=609|IndexInSheet=11|OwnerPartId=-1|Location.X=586|Location.Y=542|Color=8388608|FontID=6|IsHidden=T|Text=0603|Name=SIZE
|RECORD=41|OwnerIndex=609|IndexInSheet=12|OwnerPartId=-1|Location.X=586|Location.Y=542|Color=8388608|FontID=6|IsHidden=T|Text=GENERIC|Name=SUB
|RECORD=41|OwnerIndex=609|IndexInSheet=13|OwnerPartId=-1|Location.X=586|Location.Y=542|Color=8388608|FontID=1|IsHidden=T|Text=*|Name=SHEETPART
|RECORD=41|OwnerIndex=609|IndexInSheet=14|OwnerPartId=-1|Location.X=586|Location.Y=542|Color=8388608|FontID=1|IsHidden=T|Text=RES, 47K, 1%, 1/10W, TF, 0603|Name=DESC
|RECORD=41|OwnerIndex=609|IndexInSheet=15|OwnerPartId=-1|Location.X=586|Location.Y=542|Color=8388608|FontID=1|IsHidden=T|Text=Digi-Key|Name=Supplier 1|ReadOnlyState=3
|RECORD=41|OwnerIndex=609|IndexInSheet=16|OwnerPartId=-1|Location.X=586|Location.Y=542|Color=8388608|FontID=1|IsHidden=T|Text=P47.0KHCT-ND|Name=Supplier Part Number 1|ReadOnlyState=3
|RECORD=41|OwnerIndex=609|IndexInSheet=17|OwnerPartId=-1|Location.X=594|Location.Y=505|Color=8388608|FontID=6|Text=47K|Name=VALUE
|RECORD=2|OwnerIndex=609|OwnerPartId=1|FormalType=1|Electrical=4|PinConglomerate=35|PinLength=10|Location.X=590|Location.Y=500|Name=1|Designator=1|PinPropagationDelay=0.000000E+000
|RECORD=2|OwnerIndex=609|OwnerPartId=1|FormalType=1|Electrical=4|PinConglomerate=33|PinLength=10|Location.X=590|Location.Y=530|Name=2|Designator=2|PinPropagationDelay=0.000000E+000
|RECORD=6|OwnerIndex=609|IsNotAccesible=T|IndexInSheet=20|OwnerPartId=1|LineWidth=1|Color=16711680|LocationCount=7|X1=590|Y1=530|X2=587|Y2=527|X3=593|Y3=521|X4=587|Y4=515|X5=593|Y5=509|X6=587|Y6=503|X7=590|Y7=500
|RECORD=41|OwnerIndex=609|IndexInSheet=21|OwnerPartId=-1|Location.X=586|Location.Y=542|Color=8388608|FontID=1|IsHidden=T|Text=<VELENTIUM>|Name=VELENTIUM PART NUM
|RECORD=34|OwnerIndex=609|IndexInSheet=-1|OwnerPartId=-1|Location.X=594|Location.Y=517|Color=8388608|FontID=1|Text=R3|Name=Designator|ReadOnlyState=1
|RECORD=41|OwnerIndex=609|IndexInSheet=-1|OwnerPartId=-1|Location.X=586|Location.Y=542|Color=8388608|FontID=1|IsHidden=T|Text==MFG PART NUM|Name=Comment
|RECORD=44|OwnerIndex=609
|RECORD=45|OwnerIndex=636|IndexInSheet=-1|Description=Chip Resistor, 0603, 2-Leads, Body 1.57x0.85mm, IPC Medium Density|UseComponentLibrary=T|ModelName=RESC1608X50N|ModelType=PCBLIB|DatafileCount=1|ModelDatafileEntity0=RESC1608X50N|ModelDatafileKind0=PCBLib|IsCurrent=T|DatalinksLocked=T|DatabaseDatalinksLocked=T|IntegratedModel=T|DatabaseModel=T
|RECORD=46|OwnerIndex=637
|RECORD=48|OwnerIndex=637
|RECORD=1|LibReference=RES_0603_10K|ComponentDescription=RES, 10K, 1%, 1/10W, TF, 0603|PartCount=2|DisplayModeCount=1|IndexInSheet=33|OwnerPartId=-1|Location.X=810|Location.Y=310|Orientation=1|CurrentPartId=1|LibraryPath=*|SourceLibraryName=Resistors.IntLib|TargetFileName=*|AreaColor=11599871|Color=128|PartIDLocked=F|DesignItemId=RES_0603_10K|AllPinCount=2
|RECORD=41|OwnerIndex=640|OwnerPartId=-1|Location.X=806|Location.Y=362|Color=8388608|FontID=6|IsHidden=T|Text=7/25/2013|Name=ModifyDate
|RECORD=41|OwnerIndex=640|IndexInSheet=1|OwnerPartId=-1|Location.X=806|Location.Y=362|Color=8388608|FontID=6|IsHidden=T|Text=ERJ-3EKF1002V|Name=MFG PART NUM
|RECORD=41|OwnerIndex=640|IndexInSheet=2|OwnerPartId=-1|Location.X=806|Location.Y=362|Color=8388608|FontID=6|IsHidden=T|Text=PANASONIC|Name=MFG NAME
|RECORD=41|OwnerIndex=640|IndexInSheet=3|OwnerPartId=-1|Location.X=806|Location.Y=362|Color=8388608|FontID=6|IsHidden=T|Text=RES|Name=CATEGORY
|RECORD=41|OwnerIndex=640|IndexInSheet=4|OwnerPartId=-1|Location.X=806|Location.Y=362|Color=8388608|FontID=6|IsHidden=T|Text=7/26/2013|Name=Date
|RECORD=41|OwnerIndex=640|IndexInSheet=5|OwnerPartId=-1|Location.X=806|Location.Y=362|Color=8388608|FontID=6|IsHidden=T|Text=1%|Name=P1
|RECORD=41|OwnerIndex=640|IndexInSheet=6|OwnerPartId=-1|Location.X=806|Location.Y=362|Color=8388608|FontID=6|IsHidden=T|Text=TF|Name=P3
|RECORD=41|OwnerIndex=640|IndexInSheet=7|OwnerPartId=-1|Location.X=806|Location.Y=362|Color=8388608|FontID=6|IsHidden=T|Text=1/10W|Name=P2
|RECORD=41|OwnerIndex=640|IndexInSheet=8|OwnerPartId=-1|Location.X=806|Location.Y=362|Color=8388608|FontID=6|IsHidden=T|Text=125C|Name=MAXTEMP
|RECORD=41|OwnerIndex=640|IndexInSheet=9|OwnerPartId=-1|Location.X=806|Location.Y=362|Color=8388608|FontID=6|IsHidden=T|Text=-55C|Name=MINTEMP
|RECORD=41|OwnerIndex=640|IndexInSheet=10|OwnerPartId=-1|Location.X=806|Location.Y=362|Color=8388608|FontID=6|IsHidden=T|Text=100PPM|Name=OTHER
|RECORD=41|OwnerIndex=640|IndexInSheet=11|OwnerPartId=-1|Location.X=806|Location.Y=362|Color=8388608|FontID=6|IsHidden=T|Text=0603|Name=SIZE
|RECORD=41|OwnerIndex=640|IndexInSheet=12|OwnerPartId=-1|Location.X=806|Location.Y=362|Color=8388608|FontID=6|IsHidden=T|Text=GENERIC|Name=SUB
|RECORD=41|OwnerIndex=640|IndexInSheet=13|OwnerPartId=-1|Location.X=806|Location.Y=362|Color=8388608|FontID=6|IsHidden=T|Text=Digi-Key|Name=Supplier 1|ReadOnlyState=3
|RECORD=41|OwnerIndex=640|IndexInSheet=14|OwnerPartId=-1|Location.X=806|Location.Y=362|Color=8388608|FontID=6|IsHidden=T|Text=P10.0KHCT-ND|Name=Supplier Part Number 1|ReadOnlyState=3
|RECORD=41|OwnerIndex=640|IndexInSheet=15|OwnerPartId=-1|Location.X=806|Location.Y=362|Color=8388608|FontID=1|IsHidden=T|Text=*|Name=SHEETPART
|RECORD=41|OwnerIndex=640|IndexInSheet=16|OwnerPartId=-1|Location.X=806|Location.Y=362|Color=8388608|FontID=1|IsHidden=T|Text=RES, 10K, 1%, 1/10W, TF, 0603|Name=DESC
|RECORD=41|OwnerIndex=640|IndexInSheet=17|OwnerPartId=-1|Location.X=814|Location.Y=325|Color=8388608|FontID=6|Text=10K|Name=VALUE
|RECORD=2|OwnerIndex=640|OwnerPartId=1|FormalType=1|Electrical=4|PinConglomerate=35|PinLength=10|Location.X=810|Location.Y=320|Name=1|Designator=1|PinPropagationDelay=0.000000E+000
|RECORD=2|OwnerIndex=640|OwnerPartId=1|FormalType=1|Electrical=4|PinConglomerate=33|PinLength=10|Location.X=810|Location.Y=350|Name=2|Designator=2|PinPropagationDelay=0.000000E+000
|RECORD=6|OwnerIndex=640|IsNotAccesible=T|IndexInSheet=20|OwnerPartId=1|LineWidth=1|Color=16711680|LocationCount=7|X1=810|Y1=350|X2=807|Y2=347|X3=813|Y3=341|X4=807|Y4=335|X5=813|Y5=329|X6=807|Y6=323|X7=810|Y7=320
|RECORD=41|OwnerIndex=640|IndexInSheet=21|OwnerPartId=-1|Location.X=806|Location.Y=362|Color=8388608|FontID=1|IsHidden=T|Text=<VELENTIUM>|Name=VELENTIUM PART NUM
|RECORD=34|OwnerIndex=640|IndexInSheet=-1|OwnerPartId=-1|Location.X=814|Location.Y=337|Color=8388608|FontID=1|Text=R7|Name=Designator|ReadOnlyState=1
|RECORD=41|OwnerIndex=640|IndexInSheet=-1|OwnerPartId=-1|Location.X=806|Location.Y=362|Color=8388608|FontID=1|IsHidden=T|Text==MFG PART NUM|Name=Comment
|RECORD=44|OwnerIndex=640
|RECORD=45|OwnerIndex=667|IndexInSheet=-1|Description=Chip Resistor, 0603, 2-Leads, Body 1.57x0.85mm, IPC Medium Density|UseComponentLibrary=T|ModelName=RESC1608X50N|ModelType=PCBLIB|DatafileCount=1|ModelDatafileEntity0=RESC1608X50N|ModelDatafileKind0=PCBLib|IsCurrent=T|DatalinksLocked=T|DatabaseDatalinksLocked=T|IntegratedModel=T|DatabaseModel=T
|RECORD=46|OwnerIndex=668
|RECORD=48|OwnerIndex=668
|RECORD=1|LibReference=RES_0603_2.2K|ComponentDescription=RES, 2.2K, 1%, 1/10W, TF, 0603|PartCount=2|DisplayModeCount=1|IndexInSheet=34|OwnerPartId=-1|Location.X=670|Location.Y=280|CurrentPartId=1|LibraryPath=*|SourceLibraryName=Resistors.IntLib|TargetFileName=*|AreaColor=11599871|Color=128|PartIDLocked=F|DesignItemId=RES_0603_2.2K|AllPinCount=2
|RECORD=41|OwnerIndex=671|OwnerPartId=-1|Location.X=670|Location.Y=280|Color=8388608|FontID=6|IsHidden=T|Text=8/15/2013|Name=ModifyDate
|RECORD=41|OwnerIndex=671|IndexInSheet=1|OwnerPartId=-1|Location.X=670|Location.Y=280|Color=8388608|FontID=6|IsHidden=T|Text=ERJ-3EKF2201V|Name=MFG PART NUM
|RECORD=41|OwnerIndex=671|IndexInSheet=2|OwnerPartId=-1|Location.X=670|Location.Y=280|Color=8388608|FontID=6|IsHidden=T|Text=PANASONIC|Name=MFG NAME
|RECORD=41|OwnerIndex=671|IndexInSheet=3|OwnerPartId=-1|Location.X=670|Location.Y=280|Color=8388608|FontID=6|IsHidden=T|Text=RES|Name=CATEGORY
|RECORD=41|OwnerIndex=671|IndexInSheet=4|OwnerPartId=-1|Location.X=668|Location.Y=290|Color=8388608|FontID=6|IsHidden=T|Text=8/15/2013|Name=Date
|RECORD=41|OwnerIndex=671|IndexInSheet=5|OwnerPartId=-1|Location.X=660|Location.X_Frac=55769|Location.Y=290|Color=8388608|FontID=6|IsHidden=T|Text=1%|Name=P1
|RECORD=41|OwnerIndex=671|IndexInSheet=6|OwnerPartId=-1|Location.X=660|Location.X_Frac=55769|Location.Y=290|Color=8388608|FontID=6|IsHidden=T|Text=TF|Name=P3
|RECORD=41|OwnerIndex=671|IndexInSheet=7|OwnerPartId=-1|Location.X=660|Location.X_Frac=55769|Location.Y=290|Color=8388608|FontID=6|IsHidden=T|Text=1/10W|Name=P2
|RECORD=41|OwnerIndex=671|IndexInSheet=8|OwnerPartId=-1|Location.X=660|Location.X_Frac=55769|Location.Y=290|Color=8388608|FontID=6|IsHidden=T|Text=125C|Name=MAXTEMP
|RECORD=41|OwnerIndex=671|IndexInSheet=9|OwnerPartId=-1|Location.X=660|Location.X_Frac=55769|Location.Y=290|Color=8388608|FontID=6|IsHidden=T|Text=-55C|Name=MINTEMP
|RECORD=41|OwnerIndex=671|IndexInSheet=10|OwnerPartId=-1|Location.X=660|Location.X_Frac=55769|Location.Y=290|Color=8388608|FontID=6|IsHidden=T|Text=100PPM|Name=OTHER
|RECORD=41|OwnerIndex=671|IndexInSheet=11|OwnerPartId=-1|Location.X=660|Location.X_Frac=55769|Location.Y=290|Color=8388608|FontID=6|IsHidden=T|Text=0603|Name=SIZE
|RECORD=41|OwnerIndex=671|IndexInSheet=12|OwnerPartId=-1|Location.X=660|Location.X_Frac=55769|Location.Y=290|Color=8388608|FontID=6|IsHidden=T|Text=GENERIC|Name=SUB
|RECORD=41|OwnerIndex=671|IndexInSheet=13|OwnerPartId=-1|Location.X=655|Location.X_Frac=98077|Location.Y=294|Color=8388608|FontID=6|IsHidden=T|Text=Digi-Key|Name=Supplier 1|ReadOnlyState=3
|RECORD=41|OwnerIndex=671|IndexInSheet=14|OwnerPartId=-1|Location.X=655|Location.X_Frac=98077|Location.Y=294|Color=8388608|FontID=6|IsHidden=T|Text=P2.20KHCT-ND|Name=Supplier Part Number 1|ReadOnlyState=3
|RECORD=41|OwnerIndex=671|IndexInSheet=15|OwnerPartId=-1|Location.X=655|Location.X_Frac=98077|Location.Y=266|Color=8388608|FontID=1|IsHidden=T|Text=*|Name=SHEETPART
|RECORD=41|OwnerIndex=671|IndexInSheet=16|OwnerPartId=-1|Location.X=655|Location.X_Frac=98077|Location.Y=294|Color=8388608|FontID=1|IsHidden=T|Text=RES, 2.2K, 1%, 1/10W, TF, 0603|Name=DESC
|RECORD=41|OwnerIndex=671|IndexInSheet=17|OwnerPartId=-1|Location.X=679|Location.Y=264|Color=8388608|FontID=6|Text=2.2K|Name=VALUE
|RECORD=2|OwnerIndex=671|OwnerPartId=1|FormalType=1|Electrical=4|PinConglomerate=34|PinLength=10|Location.X=680|Location.Y=280|Name=1|Designator=1|PinPropagationDelay=0.000000E+000
|RECORD=2|OwnerIndex=671|OwnerPartId=1|FormalType=1|Electrical=4|PinConglomerate=32|PinLength=10|Location.X=710|Location.Y=280|Name=2|Designator=2|PinPropagationDelay=0.000000E+000
|RECORD=6|OwnerIndex=671|IsNotAccesible=T|IndexInSheet=20|OwnerPartId=1|LineWidth=1|Color=16711680|LocationCount=7|X1=710|Y1=280|X2=707|Y2=283|X3=701|Y3=277|X4=695|Y4=283|X5=689|Y5=277|X6=683|Y6=283|X7=680|Y7=280
|RECORD=41|OwnerIndex=671|IndexInSheet=21|OwnerPartId=-1|Location.X=656|Location.X_Frac=61102|Location.Y=294|Color=8388608|FontID=1|IsHidden=T|Text=<VELENTIUM>|Name=VELENTIUM PART NUM
|RECORD=34|OwnerIndex=671|IndexInSheet=-1|OwnerPartId=-1|Location.X=679|Location.Y=284|Color=8388608|FontID=1|Text=R9|Name=Designator|ReadOnlyState=1
|RECORD=41|OwnerIndex=671|IndexInSheet=-1|OwnerPartId=-1|Location.X=690|Location.Y=270|Color=8388608|FontID=1|IsHidden=T|Text==MFG PART NUM|Name=Comment
|RECORD=44|OwnerIndex=671
|RECORD=45|OwnerIndex=698|IndexInSheet=-1|Description=Chip Resistor, 0603, 2-Leads, Body 1.57x0.85mm, IPC Medium Density|UseComponentLibrary=T|ModelName=RESC1608X50N|ModelType=PCBLIB|DatafileCount=1|ModelDatafileEntity0=RESC1608X50N|ModelDatafileKind0=PCBLib|IsCurrent=T|DatalinksLocked=T|DatabaseDatalinksLocked=T|IntegratedModel=T|DatabaseModel=T
|RECORD=46|OwnerIndex=699
|RECORD=48|OwnerIndex=699
|RECORD=1|LibReference=RES_0603_26.1K|ComponentDescription=RES, 26.1K, 1%, 1/10W, TF, 0603|PartCount=2|DisplayModeCount=1|IndexInSheet=35|OwnerPartId=-1|Location.X=870|Location.Y=430|CurrentPartId=1|LibraryPath=*|SourceLibraryName=Resistors.IntLib|TargetFileName=*|AreaColor=11599871|Color=128|PartIDLocked=F|DesignItemId=RES_0603_26.1K|AllPinCount=2
|RECORD=41|OwnerIndex=702|OwnerPartId=-1|Location.X=870|Location.Y=430|Color=8388608|FontID=6|IsHidden=T|Text=7/25/2013|Name=ModifyDate
|RECORD=41|OwnerIndex=702|IndexInSheet=1|OwnerPartId=-1|Location.X=870|Location.Y=430|Color=8388608|FontID=6|IsHidden=T|Text=ERJ-3EKF2612V|Name=MFG PART NUM
|RECORD=41|OwnerIndex=702|IndexInSheet=2|OwnerPartId=-1|Location.X=870|Location.Y=430|Color=8388608|FontID=6|IsHidden=T|Text=PANASONIC|Name=MFG NAME
|RECORD=41|OwnerIndex=702|IndexInSheet=3|OwnerPartId=-1|Location.X=870|Location.Y=430|Color=8388608|FontID=6|IsHidden=T|Text=RES|Name=CATEGORY
|RECORD=41|OwnerIndex=702|IndexInSheet=4|OwnerPartId=-1|Location.X=868|Location.Y=440|Color=8388608|FontID=6|IsHidden=T|Text=7/26/2013|Name=Date
|RECORD=41|OwnerIndex=702|IndexInSheet=5|OwnerPartId=-1|Location.X=860|Location.X_Frac=55769|Location.Y=440|Color=8388608|FontID=6|IsHidden=T|Text=1%|Name=P1
|RECORD=41|OwnerIndex=702|IndexInSheet=6|OwnerPartId=-1|Location.X=860|Location.X_Frac=55769|Location.Y=440|Color=8388608|FontID=6|IsHidden=T|Text=TF|Name=P3
|RECORD=41|OwnerIndex=702|IndexInSheet=7|OwnerPartId=-1|Location.X=860|Location.X_Frac=55769|Location.Y=440|Color=8388608|FontID=6|IsHidden=T|Text=1/10W|Name=P2
|RECORD=41|OwnerIndex=702|IndexInSheet=8|OwnerPartId=-1|Location.X=860|Location.X_Frac=55769|Location.Y=440|Color=8388608|FontID=6|IsHidden=T|Text=125C|Name=MAXTEMP
|RECORD=41|OwnerIndex=702|IndexInSheet=9|OwnerPartId=-1|Location.X=860|Location.X_Frac=55769|Location.Y=440|Color=8388608|FontID=6|IsHidden=T|Text=-55C|Name=MINTEMP
|RECORD=41|OwnerIndex=702|IndexInSheet=10|OwnerPartId=-1|Location.X=860|Location.X_Frac=55769|Location.Y=440|Color=8388608|FontID=6|IsHidden=T|Text=100PPM|Name=OTHER
|RECORD=41|OwnerIndex=702|IndexInSheet=11|OwnerPartId=-1|Location.X=860|Location.X_Frac=55769|Location.Y=440|Color=8388608|FontID=6|IsHidden=T|Text=0603|Name=SIZE
|RECORD=41|OwnerIndex=702|IndexInSheet=12|OwnerPartId=-1|Location.X=860|Location.X_Frac=55769|Location.Y=440|Color=8388608|FontID=6|IsHidden=T|Text=GENERIC|Name=SUB
|RECORD=41|OwnerIndex=702|IndexInSheet=13|OwnerPartId=-1|Location.X=855|Location.X_Frac=98077|Location.Y=416|Color=8388608|FontID=1|IsHidden=T|Text=*|Name=SHEETPART
|RECORD=41|OwnerIndex=702|IndexInSheet=14|OwnerPartId=-1|Location.X=855|Location.X_Frac=98077|Location.Y=444|Color=8388608|FontID=1|IsHidden=T|Text=RES, 27.1K, 1%, 1/10W, TF, 0603|Name=DESC
|RECORD=41|OwnerIndex=702|IndexInSheet=15|OwnerPartId=-1|Location.X=856|Location.X_Frac=61102|Location.Y=444|Color=8388608|FontID=1|IsHidden=T|Text=<VELENTIUM>|Name=VELENTIUM PART NUM
|RECORD=41|OwnerIndex=702|IndexInSheet=16|OwnerPartId=-1|Location.X=855|Location.X_Frac=98077|Location.Y=444|Color=8388608|FontID=1|IsHidden=T|Text=Digi-Key|Name=Supplier 1|ReadOnlyState=3
|RECORD=41|OwnerIndex=702|IndexInSheet=17|OwnerPartId=-1|Location.X=855|Location.X_Frac=98077|Location.Y=444|Color=8388608|FontID=1|IsHidden=T|Text=P26.1KHCT-ND|Name=Supplier Part Number 1|ReadOnlyState=3
|RECORD=41|OwnerIndex=702|IndexInSheet=18|OwnerPartId=-1|Location.X=879|Location.Y=414|Color=8388608|FontID=6|Text=26.1K|Name=VALUE
|RECORD=2|OwnerIndex=702|OwnerPartId=1|FormalType=1|Electrical=4|PinConglomerate=34|PinLength=10|Location.X=880|Location.Y=430|Name=1|Designator=1|PinPropagationDelay=0.000000E+000
|RECORD=2|OwnerIndex=702|OwnerPartId=1|FormalType=1|Electrical=4|PinConglomerate=32|PinLength=10|Location.X=910|Location.Y=430|Name=2|Designator=2|PinPropagationDelay=0.000000E+000
|RECORD=6|OwnerIndex=702|IsNotAccesible=T|IndexInSheet=21|OwnerPartId=1|LineWidth=1|Color=16711680|LocationCount=7|X1=910|Y1=430|X2=907|Y2=433|X3=901|Y3=427|X4=895|Y4=433|X5=889|Y5=427|X6=883|Y6=433|X7=880|Y7=430
|RECORD=34|OwnerIndex=702|IndexInSheet=-1|OwnerPartId=-1|Location.X=879|Location.Y=434|Color=8388608|FontID=1|Text=R5|Name=Designator|ReadOnlyState=1
|RECORD=41|OwnerIndex=702|IndexInSheet=-1|OwnerPartId=-1|Location.X=890|Location.Y=420|Color=8388608|FontID=1|IsHidden=T|Text==MFG PART NUM|Name=Comment
|RECORD=44|OwnerIndex=702
|RECORD=45|OwnerIndex=729|IndexInSheet=-1|Description=Chip Resistor, 0603, 2-Leads, Body 1.57x0.85mm, IPC Medium Density|UseComponentLibrary=T|ModelName=RESC1608X50N|ModelType=PCBLIB|DatafileCount=1|ModelDatafileEntity0=RESC1608X50N|ModelDatafileKind0=PCBLib|IsCurrent=T|DatalinksLocked=T|DatabaseDatalinksLocked=T|IntegratedModel=T|DatabaseModel=T
|RECORD=46|OwnerIndex=730
|RECORD=48|OwnerIndex=730
|RECORD=1|LibReference=MP1482DS|ComponentDescription=IC, DC/DC, MP1482DS, >4.75VIN, 0.923-15V OUT, SOIC8|PartCount=2|DisplayModeCount=1|IndexInSheet=36|OwnerPartId=-1|Location.X=715|Location.Y=855|CurrentPartId=1|LibraryPath=*|SourceLibraryName=IntegratedCircuits.IntLib|TargetFileName=*|AreaColor=11599871|Color=128|PartIDLocked=F|DesignItemId=MP1482DS|AllPinCount=8
|RECORD=41|OwnerIndex=733|OwnerPartId=-1|Location.X=715|Location.Y=855|Color=8388608|FontID=6|IsHidden=T|Text=MP1482DS-LF|Name=MFG PART NUM
|RECORD=41|OwnerIndex=733|IndexInSheet=1|OwnerPartId=-1|Location.X=715|Location.Y=855|Color=8388608|FontID=6|IsHidden=T|Text=12/27/2005 8:34:25 AM|Name=MODIFY DATE
|RECORD=41|OwnerIndex=733|IndexInSheet=2|OwnerPartId=-1|Location.X=715|Location.Y=855|Color=8388608|FontID=6|IsHidden=T|Text=MPS|Name=MFG NAME
|RECORD=41|OwnerIndex=733|IndexInSheet=3|OwnerPartId=-1|Location.X=643|Location.Y=1030|Color=8388608|FontID=6|IsHidden=T|Text=IC, DC/DC|Name=CATEGORY
|RECORD=41|OwnerIndex=733|IndexInSheet=4|OwnerPartId=-1|Location.X=643|Location.Y=1030|Color=8388608|FontID=6|IsHidden=T|Name=DATE
|RECORD=41|OwnerIndex=733|IndexInSheet=5|OwnerPartId=-1|Location.X=643|Location.Y=1030|Color=8388608|FontID=6|IsHidden=T|Text=+85C|Name=MAXTEMP
|RECORD=41|OwnerIndex=733|IndexInSheet=6|OwnerPartId=-1|Location.X=643|Location.Y=1030|Color=8388608|FontID=6|IsHidden=T|Text=-40C|Name=MINTEMP
|RECORD=41|OwnerIndex=733|IndexInSheet=7|OwnerPartId=-1|Location.X=643|Location.Y=1030|Color=8388608|FontID=6|IsHidden=T|Text=additional spec|Name=OTHER
|RECORD=41|OwnerIndex=733|IndexInSheet=8|OwnerPartId=-1|Location.X=643|Location.Y=1030|Color=8388608|FontID=6|IsHidden=T|Text=>4.75V IN|Name=P1
|RECORD=41|OwnerIndex=733|IndexInSheet=9|OwnerPartId=-1|Location.X=643|Location.Y=1030|Color=8388608|FontID=6|IsHidden=T|Text=0.923-15V OUT|Name=P2
|RECORD=41|OwnerIndex=733|IndexInSheet=10|OwnerPartId=-1|Location.X=643|Location.Y=1030|Color=8388608|FontID=6|IsHidden=T|Text=W|Name=P3
|RECORD=41|OwnerIndex=733|IndexInSheet=11|OwnerPartId=-1|Location.X=643|Location.Y=1030|Color=8388608|FontID=6|IsHidden=T|Text=8SOIC|Name=SIZE
|RECORD=41|OwnerIndex=733|IndexInSheet=12|OwnerPartId=-1|Location.X=643|Location.Y=1030|Color=8388608|FontID=6|IsHidden=T|Name=SUB
|RECORD=41|OwnerIndex=733|IndexInSheet=13|OwnerPartId=-1|Location.X=643|Location.Y=843|Color=8388608|FontID=1|IsHidden=T|Text=*|Name=SHEETPART
|RECORD=41|OwnerIndex=733|IndexInSheet=14|OwnerPartId=-1|Location.X=643|Location.Y=1006|Color=8388608|FontID=1|IsHidden=T|Text=IC, DC/DC, MP1482DS, >4.75VIN, 0.923-15V OUT, SOIC8|Name=DESC
|RECORD=41|OwnerIndex=733|IndexInSheet=15|OwnerPartId=-1|Location.X=643|Location.Y=1006|Color=8388608|FontID=1|IsHidden=T|Text=<V PART NUM>|Name=VELENTIUM PART NUM
|RECORD=41|OwnerIndex=733|IndexInSheet=16|OwnerPartId=-1|Location.X=628|Location.Y=932|Color=8388608|FontID=1|IsHidden=T|Text=Digi-Key|Name=Supplier 1|ReadOnlyState=3
|RECORD=41|OwnerIndex=733|IndexInSheet=17|OwnerPartId=-1|Location.X=628|Location.Y=932|Color=8388608|FontID=1|IsHidden=T|Text=1589-1524-1-ND|Name=Supplier Part Number 1|ReadOnlyState=3
|RECORD=41|OwnerIndex=733|IndexInSheet=18|OwnerPartId=-1|Location.X=790|Location.Y=890|Color=8388608|FontID=6|Text=MP1482DS|Name=VALUE
|RECORD=14|OwnerIndex=733|IsNotAccesible=T|IndexInSheet=19|OwnerPartId=1|Location.X=660|Location.Y=810|Corner.X=770|Corner.Y=900|LineWidth=1|Color=128|AreaColor=11599871|IsSolid=T|Transparent=T
|RECORD=2|OwnerIndex=733|OwnerPartId=1|FormalType=1|Electrical=4|PinConglomerate=57|PinLength=30|Location.X=740|Location.Y=900|Name=BS|Designator=1|SwapIDPart=Ž&Ž||PinPropagationDelay=0.000000E+000
|RECORD=2|OwnerIndex=733|OwnerPartId=1|FormalType=1|Electrical=4|PinConglomerate=57|PinLength=30|Location.X=690|Location.Y=900|Name=IN|Designator=2|SwapIDPart=Ž&Ž||PinPropagationDelay=0.000000E+000
|RECORD=2|OwnerIndex=733|OwnerPartId=1|FormalType=1|Electrical=4|PinConglomerate=56|PinLength=30|Location.X=770|Location.Y=870|Name=SW|Designator=3|SwapIDPart=Ž&Ž||PinPropagationDelay=0.000000E+000
|RECORD=2|OwnerIndex=733|OwnerPartId=1|FormalType=1|Electrical=4|PinConglomerate=56|PinLength=30|Location.X=770|Location.Y=840|Name=FB|Designator=5|SwapIDPart=Ž&Ž||PinPropagationDelay=0.000000E+000
|RECORD=2|OwnerIndex=733|OwnerPartId=1|FormalType=1|Electrical=4|PinConglomerate=58|PinLength=30|Location.X=660|Location.Y=870|Name=EN|Designator=7|SwapIDPart=Ž&Ž||PinPropagationDelay=0.000000E+000
|RECORD=2|OwnerIndex=733|OwnerPartId=1|FormalType=1|Electrical=4|PinConglomerate=58|PinLength=30|Location.X=660|Location.Y=840|Name=SS|Designator=8|SwapIDPart=Ž&Ž||PinPropagationDelay=0.000000E+000
|RECORD=2|OwnerIndex=733|OwnerPartId=1|FormalType=1|Electrical=4|PinConglomerate=59|PinLength=30|Location.X=690|Location.Y=810|Name=GND|Designator=4|SwapIDPart=Ž&Ž||PinPropagationDelay=0.000000E+000
|RECORD=2|OwnerIndex=733|OwnerPartId=1|FormalType=1|Electrical=4|PinConglomerate=59|PinLength=30|Location.X=740|Location.Y=810|Name=COMP|Designator=6|SwapIDPart=Ž&Ž||PinPropagationDelay=0.000000E+000
|RECORD=34|OwnerIndex=733|IndexInSheet=-1|OwnerPartId=-1|Location.X=790|Location.Y=900|Color=8388608|FontID=1|Text=U1|Name=Designator|ReadOnlyState=1
|RECORD=41|OwnerIndex=733|IndexInSheet=-1|OwnerPartId=-1|Location.X=675|Location.Y=1015|Color=8388608|FontID=1|IsHidden=T|Text=MP1482DS-LF|Name=Comment
|RECORD=44|OwnerIndex=733
|RECORD=45|OwnerIndex=772|IndexInSheet=-1|Description=SOIC127P600X175-8N|UseComponentLibrary=T|ModelName=SOIC127P600X175-8N|ModelType=PCBLIB|DatafileCount=1|ModelDatafileEntity0=SOIC127P600X175-8N|ModelDatafileKind0=PCBLib|IsCurrent=T|DatalinksLocked=T|DatabaseDatalinksLocked=T|IntegratedModel=T|DatabaseModel=T
|RECORD=46|OwnerIndex=773
|RECORD=48|OwnerIndex=773
|RECORD=1|LibReference=MP1482DS|ComponentDescription=IC, DC/DC, MP1482DS, >4.75VIN, 0.923-15V OUT, SOIC8|PartCount=2|DisplayModeCount=1|IndexInSheet=37|OwnerPartId=-1|Location.X=695|Location.Y=445|CurrentPartId=1|LibraryPath=*|SourceLibraryName=IntegratedCircuits.IntLib|TargetFileName=*|AreaColor=11599871|Color=128|PartIDLocked=F|DesignItemId=MP1482DS|AllPinCount=8
|RECORD=41|OwnerIndex=776|OwnerPartId=-1|Location.X=695|Location.Y=445|Color=8388608|FontID=6|IsHidden=T|Text=MP1482DS-LF|Name=MFG PART NUM
|RECORD=41|OwnerIndex=776|IndexInSheet=1|OwnerPartId=-1|Location.X=695|Location.Y=445|Color=8388608|FontID=6|IsHidden=T|Text=12/27/2005 8:34:25 AM|Name=MODIFY DATE
|RECORD=41|OwnerIndex=776|IndexInSheet=2|OwnerPartId=-1|Location.X=695|Location.Y=445|Color=8388608|FontID=6|IsHidden=T|Text=MPS|Name=MFG NAME
|RECORD=41|OwnerIndex=776|IndexInSheet=3|OwnerPartId=-1|Location.X=623|Location.Y=620|Color=8388608|FontID=6|IsHidden=T|Text=IC, DC/DC|Name=CATEGORY
|RECORD=41|OwnerIndex=776|IndexInSheet=4|OwnerPartId=-1|Location.X=623|Location.Y=620|Color=8388608|FontID=6|IsHidden=T|Name=DATE
|RECORD=41|OwnerIndex=776|IndexInSheet=5|OwnerPartId=-1|Location.X=623|Location.Y=620|Color=8388608|FontID=6|IsHidden=T|Text=+85C|Name=MAXTEMP
|RECORD=41|OwnerIndex=776|IndexInSheet=6|OwnerPartId=-1|Location.X=623|Location.Y=620|Color=8388608|FontID=6|IsHidden=T|Text=-40C|Name=MINTEMP
|RECORD=41|OwnerIndex=776|IndexInSheet=7|OwnerPartId=-1|Location.X=623|Location.Y=620|Color=8388608|FontID=6|IsHidden=T|Text=additional spec|Name=OTHER
|RECORD=41|OwnerIndex=776|IndexInSheet=8|OwnerPartId=-1|Location.X=623|Location.Y=620|Color=8388608|FontID=6|IsHidden=T|Text=>4.75V IN|Name=P1
|RECORD=41|OwnerIndex=776|IndexInSheet=9|OwnerPartId=-1|Location.X=623|Location.Y=620|Color=8388608|FontID=6|IsHidden=T|Text=0.923-15V OUT|Name=P2
|RECORD=41|OwnerIndex=776|IndexInSheet=10|OwnerPartId=-1|Location.X=623|Location.Y=620|Color=8388608|FontID=6|IsHidden=T|Text=W|Name=P3
|RECORD=41|OwnerIndex=776|IndexInSheet=11|OwnerPartId=-1|Location.X=623|Location.Y=620|Color=8388608|FontID=6|IsHidden=T|Text=8SOIC|Name=SIZE
|RECORD=41|OwnerIndex=776|IndexInSheet=12|OwnerPartId=-1|Location.X=623|Location.Y=620|Color=8388608|FontID=6|IsHidden=T|Name=SUB
|RECORD=41|OwnerIndex=776|IndexInSheet=13|OwnerPartId=-1|Location.X=623|Location.Y=433|Color=8388608|FontID=1|IsHidden=T|Text=*|Name=SHEETPART
|RECORD=41|OwnerIndex=776|IndexInSheet=14|OwnerPartId=-1|Location.X=623|Location.Y=596|Color=8388608|FontID=1|IsHidden=T|Text=IC, DC/DC, MP1482DS, >4.75VIN, 0.923-15V OUT, SOIC8|Name=DESC
|RECORD=41|OwnerIndex=776|IndexInSheet=15|OwnerPartId=-1|Location.X=623|Location.Y=596|Color=8388608|FontID=1|IsHidden=T|Text=<V PART NUM>|Name=VELENTIUM PART NUM
|RECORD=41|OwnerIndex=776|IndexInSheet=16|OwnerPartId=-1|Location.X=608|Location.Y=522|Color=8388608|FontID=1|IsHidden=T|Text=Digi-Key|Name=Supplier 1|ReadOnlyState=3
|RECORD=41|OwnerIndex=776|IndexInSheet=17|OwnerPartId=-1|Location.X=608|Location.Y=522|Color=8388608|FontID=1|IsHidden=T|Text=1589-1524-1-ND|Name=Supplier Part Number 1|ReadOnlyState=3
|RECORD=41|OwnerIndex=776|IndexInSheet=18|OwnerPartId=-1|Location.X=750|Location.Y=480|Color=8388608|FontID=6|Text=MP1482DS|Name=VALUE
|RECORD=14|OwnerIndex=776|IsNotAccesible=T|IndexInSheet=19|OwnerPartId=1|Location.X=640|Location.Y=400|Corner.X=750|Corner.Y=490|LineWidth=1|Color=128|AreaColor=11599871|IsSolid=T|Transparent=T
|RECORD=2|OwnerIndex=776|OwnerPartId=1|FormalType=1|Electrical=4|PinConglomerate=57|PinLength=30|Location.X=720|Location.Y=490|Name=BS|Designator=1|SwapIDPart=Ž&Ž||PinPropagationDelay=0.000000E+000
|RECORD=2|OwnerIndex=776|OwnerPartId=1|FormalType=1|Electrical=4|PinConglomerate=57|PinLength=30|Location.X=670|Location.Y=490|Name=IN|Designator=2|SwapIDPart=Ž&Ž||PinPropagationDelay=0.000000E+000
|RECORD=2|OwnerIndex=776|OwnerPartId=1|FormalType=1|Electrical=4|PinConglomerate=56|PinLength=30|Location.X=750|Location.Y=460|Name=SW|Designator=3|SwapIDPart=Ž&Ž||PinPropagationDelay=0.000000E+000
|RECORD=2|OwnerIndex=776|OwnerPartId=1|FormalType=1|Electrical=4|PinConglomerate=56|PinLength=30|Location.X=750|Location.Y=430|Name=FB|Designator=5|SwapIDPart=Ž&Ž||PinPropagationDelay=0.000000E+000
|RECORD=2|OwnerIndex=776|OwnerPartId=1|FormalType=1|Electrical=4|PinConglomerate=58|PinLength=30|Location.X=640|Location.Y=460|Name=EN|Designator=7|SwapIDPart=Ž&Ž||PinPropagationDelay=0.000000E+000
|RECORD=2|OwnerIndex=776|OwnerPartId=1|FormalType=1|Electrical=4|PinConglomerate=58|PinLength=30|Location.X=640|Location.Y=430|Name=SS|Designator=8|SwapIDPart=Ž&Ž||PinPropagationDelay=0.000000E+000
|RECORD=2|OwnerIndex=776|OwnerPartId=1|FormalType=1|Electrical=4|PinConglomerate=59|PinLength=30|Location.X=670|Location.Y=400|Name=GND|Designator=4|SwapIDPart=Ž&Ž||PinPropagationDelay=0.000000E+000
|RECORD=2|OwnerIndex=776|OwnerPartId=1|FormalType=1|Electrical=4|PinConglomerate=59|PinLength=30|Location.X=720|Location.Y=400|Name=COMP|Designator=6|SwapIDPart=Ž&Ž||PinPropagationDelay=0.000000E+000
|RECORD=34|OwnerIndex=776|IndexInSheet=-1|OwnerPartId=-1|Location.X=750|Location.Y=490|Color=8388608|FontID=1|Text=U2|Name=Designator|ReadOnlyState=1
|RECORD=41|OwnerIndex=776|IndexInSheet=-1|OwnerPartId=-1|Location.X=655|Location.Y=605|Color=8388608|FontID=1|IsHidden=T|Text=MP1482DS-LF|Name=Comment
|RECORD=44|OwnerIndex=776
|RECORD=45|OwnerIndex=815|IndexInSheet=-1|Description=SOIC127P600X175-8N|UseComponentLibrary=T|ModelName=SOIC127P600X175-8N|ModelType=PCBLIB|DatafileCount=1|ModelDatafileEntity0=SOIC127P600X175-8N|ModelDatafileKind0=PCBLib|IsCurrent=T|DatalinksLocked=T|DatabaseDatalinksLocked=T|IntegratedModel=T|DatabaseModel=T
|RECORD=46|OwnerIndex=816
|RECORD=48|OwnerIndex=816
|RECORD=1|LibReference=FUSE_0603_2.00A|ComponentDescription=FUSE SLOW 2.00A 32V M 0603|PartCount=2|DisplayModeCount=1|IndexInSheet=38|OwnerPartId=-1|Location.X=325|Location.Y=785|CurrentPartId=1|LibraryPath=*|SourceLibraryName=Passives.IntLib|TargetFileName=*|AreaColor=11599871|Color=128|PartIDLocked=F|DesignItemId=FUSE_0603_2.00A|AllPinCount=2
|RECORD=41|OwnerIndex=819|OwnerPartId=-1|Location.X=325|Location.Y=785|Color=8388608|FontID=6|IsHidden=T|Text=SF-0603S200-2|Name=MFG PART NUM
|RECORD=41|OwnerIndex=819|IndexInSheet=1|OwnerPartId=-1|Location.X=325|Location.Y=785|Color=8388608|FontID=6|IsHidden=T|Text=9/4/2013|Name=MODIFY DATE
|RECORD=41|OwnerIndex=819|IndexInSheet=2|OwnerPartId=-1|Location.X=325|Location.Y=785|Color=8388608|FontID=6|IsHidden=T|Text=BOURNS|Name=MFG NAME
|RECORD=41|OwnerIndex=819|IndexInSheet=3|OwnerPartId=-1|Location.X=325|Location.Y=785|Color=8388608|FontID=6|IsHidden=T|Text=FUSE|Name=CATEGORY
|RECORD=41|OwnerIndex=819|IndexInSheet=4|OwnerPartId=-1|Location.X=323|Location.Y=802|Color=8388608|FontID=6|IsHidden=T|Text=20 OCT 15|Name=DATE
|RECORD=41|OwnerIndex=819|IndexInSheet=5|OwnerPartId=-1|Location.X=323|Location.Y=802|Color=8388608|FontID=6|IsHidden=T|Text=105C|Name=MAXTEMP
|RECORD=41|OwnerIndex=819|IndexInSheet=6|OwnerPartId=-1|Location.X=323|Location.Y=802|Color=8388608|FontID=6|IsHidden=T|Text=-40C|Name=MINTEMP
|RECORD=41|OwnerIndex=819|IndexInSheet=7|OwnerPartId=-1|Location.X=323|Location.Y=802|Color=8388608|FontID=6|IsHidden=T|Text=UL E141069|Name=OTHER
|RECORD=41|OwnerIndex=819|IndexInSheet=8|OwnerPartId=-1|Location.X=323|Location.Y=802|Color=8388608|FontID=6|IsHidden=T|Text=SLOW BLO|Name=P1
|RECORD=41|OwnerIndex=819|IndexInSheet=9|OwnerPartId=-1|Location.X=323|Location.Y=802|Color=8388608|FontID=6|IsHidden=T|Text=32V|Name=P2
|RECORD=41|OwnerIndex=819|IndexInSheet=10|OwnerPartId=-1|Location.X=323|Location.Y=802|Color=8388608|FontID=6|IsHidden=T|Text=M|Name=P3
|RECORD=41|OwnerIndex=819|IndexInSheet=11|OwnerPartId=-1|Location.X=323|Location.Y=802|Color=8388608|FontID=6|IsHidden=T|Text=0603|Name=SIZE
|RECORD=41|OwnerIndex=819|IndexInSheet=12|OwnerPartId=-1|Location.X=323|Location.Y=802|Color=8388608|FontID=6|IsHidden=T|Name=SUB
|RECORD=41|OwnerIndex=819|IndexInSheet=13|OwnerPartId=-1|Location.X=323|Location.Y=758|Color=8388608|FontID=1|IsHidden=T|Text=*|Name=SHEETPART
|RECORD=41|OwnerIndex=819|IndexInSheet=14|OwnerPartId=-1|Location.X=323|Location.Y=806|Color=8388608|FontID=1|IsHidden=T|Text=FUSE SLOW 1.25A 32V M 0603|Name=DESC
|RECORD=41|OwnerIndex=819|IndexInSheet=15|OwnerPartId=-1|Location.X=323|Location.Y=806|Color=8388608|FontID=1|IsHidden=T|Text=<VALENTIUM>|Name=VALENTIUM PART NUM
|RECORD=41|OwnerIndex=819|IndexInSheet=16|OwnerPartId=-1|Location.X=323|Location.Y=806|Color=8388608|FontID=1|IsHidden=T|Text=Digi-Key|Name=Supplier 1|ReadOnlyState=3
|RECORD=2|OwnerIndex=819|OwnerPartId=1|FormalType=1|Electrical=4|PinConglomerate=34|PinLength=20|Location.X=345|Location.Y=785|Name=1|Designator=1|SwapIdPin=1|SwapIDPart=1|PinPropagationDelay=0.000000E+000
|RECORD=2|OwnerIndex=819|OwnerPartId=1|FormalType=1|Electrical=4|PinConglomerate=32|PinLength=20|Location.X=365|Location.Y=785|Name=2|Designator=2|SwapIdPin=2|SwapIDPart=1|PinPropagationDelay=0.000000E+000
|RECORD=12|OwnerIndex=819|IsNotAccesible=T|IndexInSheet=19|OwnerPartId=1|Location.X=360|Location.Y=785|Radius=5|LineWidth=1|StartAngle=180.000|Color=16711680
|RECORD=12|OwnerIndex=819|IsNotAccesible=T|IndexInSheet=20|OwnerPartId=1|Location.X=350|Location.Y=785|Radius=5|LineWidth=1|EndAngle=180.000|Color=16711680
|RECORD=41|OwnerIndex=819|IndexInSheet=21|OwnerPartId=-1|Location.X=343|Location.Y=763|Color=8388608|FontID=6|Text=2.00A|Name=VALUE
|RECORD=8|OwnerIndex=819|IsNotAccesible=T|IndexInSheet=22|OwnerPartId=1|Location.X=345|Location.Y=785|Radius=2|SecondaryRadius=2|LineWidth=1|Color=16711680|AreaColor=16777215|IsSolid=T
|RECORD=8|OwnerIndex=819|IsNotAccesible=T|IndexInSheet=23|OwnerPartId=1|Location.X=365|Location.Y=785|Radius=2|SecondaryRadius=2|LineWidth=1|Color=16711680|AreaColor=16777215|IsSolid=T
|RECORD=41|OwnerIndex=819|IndexInSheet=24|OwnerPartId=-1|Location.X=343|Location.Y=758|Color=8388608|FontID=1|IsHidden=T|Text=SF-0603S200-2CT-ND|Name=Supplier Part Number 1|ReadOnlyState=3
|RECORD=34|OwnerIndex=819|IndexInSheet=-1|OwnerPartId=-1|Location.X=343|Location.Y=790|Color=8388608|FontID=1|Text=F1|Name=Designator|ReadOnlyState=1
|RECORD=41|OwnerIndex=819|IndexInSheet=-1|OwnerPartId=-1|Location.X=365|Location.Y=762|Location.Y_Frac=10000|Color=8388608|FontID=1|IsHidden=T|Text=FUSE_0603_2.00A|Name=Comment
|RECORD=44|OwnerIndex=819
|RECORD=45|OwnerIndex=849|IndexInSheet=-1|Description=Chip Fuse, 0603, 2-Leads, Body 1.60x0.81mm, IPC Medium Density|UseComponentLibrary=T|ModelName=FUSM1608X60N|ModelType=PCBLIB|DatafileCount=1|ModelDatafileEntity0=FUSM1608X60N|ModelDatafileKind0=PCBLib|IsCurrent=T|DatalinksLocked=T|DatabaseDatalinksLocked=T|IntegratedModel=T|DatabaseModel=T
|RECORD=46|OwnerIndex=850
|RECORD=48|OwnerIndex=850
|RECORD=1|LibReference=CAP|ComponentDescription=C0603X104K5RACAUTO|PartCount=2|DisplayModeCount=2|IndexInSheet=39|OwnerPartId=-1|Location.X=462|Location.Y=727|Orientation=1|CurrentPartId=1|SourceLibraryName=Altium Content Vault|TargetFileName=*|AreaColor=11599871|Color=128|PartIDLocked=F|DesignItemId=CMP-2006-00003-1|AllPinCount=2
|RECORD=2|OwnerIndex=853|OwnerPartId=1|OwnerPartDisplayMode=1|FormalType=1|Electrical=4|PinConglomerate=35|PinLength=10|Location.X=472|Location.Y=727|Name=1|Designator=1|PinPropagationDelay=0.000000E+000
|RECORD=2|OwnerIndex=853|OwnerPartId=1|OwnerPartDisplayMode=1|FormalType=1|Electrical=4|PinConglomerate=33|PinLength=10|Location.X=472|Location.Y=737|Name=2|Designator=2|PinPropagationDelay=0.000000E+000
|RECORD=13|OwnerIndex=853|IsNotAccesible=T|IndexInSheet=2|OwnerPartId=1|OwnerPartDisplayMode=1|Location.X=480|Location.Y=727|Corner.X=464|Corner.Y=727|LineWidth=1|Color=16711680
|RECORD=13|OwnerIndex=853|IsNotAccesible=T|IndexInSheet=3|OwnerPartId=1|OwnerPartDisplayMode=1|Location.X=472|Location.Y=731|Corner.X=472|Corner.Y=737|LineWidth=1|Color=16711680
|RECORD=12|OwnerIndex=853|IsNotAccesible=T|IndexInSheet=4|OwnerPartId=1|OwnerPartDisplayMode=1|Location.X=472|Location.Y=747|Radius=16|LineWidth=1|StartAngle=241.000|EndAngle=270.000|Color=16711680
|RECORD=12|OwnerIndex=853|IsNotAccesible=T|IndexInSheet=5|OwnerPartId=1|OwnerPartDisplayMode=1|Location.X=472|Location.Y=747|Radius=16|LineWidth=1|StartAngle=270.000|EndAngle=299.000|Color=16711680
|RECORD=2|OwnerIndex=853|OwnerPartId=1|FormalType=1|Electrical=4|PinConglomerate=35|PinLength=10|Location.X=472|Location.Y=727|Name=1|Designator=1|PinPropagationDelay=0.000000E+000
|RECORD=2|OwnerIndex=853|OwnerPartId=1|FormalType=1|Electrical=4|PinConglomerate=33|PinLength=10|Location.X=472|Location.Y=737|Name=2|Designator=2|PinPropagationDelay=0.000000E+000
|RECORD=13|OwnerIndex=853|IsNotAccesible=T|IndexInSheet=8|OwnerPartId=1|Location.X=464|Location.Y=734|Corner.X=480|Corner.Y=734|LineWidth=1|Color=16711680
|RECORD=13|OwnerIndex=853|IsNotAccesible=T|IndexInSheet=9|OwnerPartId=1|Location.X=480|Location.Y=730|Corner.X=464|Corner.Y=730|LineWidth=1|Color=16711680
|RECORD=6|OwnerIndex=853|IsNotAccesible=T|IndexInSheet=10|OwnerPartId=1|LineWidth=1|Color=16711680|LocationCount=2|X1=472|Y1=727|X2=472|Y2=730
|RECORD=6|OwnerIndex=853|IsNotAccesible=T|IndexInSheet=11|OwnerPartId=1|LineWidth=1|Color=16711680|LocationCount=2|X1=472|Y1=737|X2=472|Y2=734
|RECORD=41|OwnerIndex=853|IndexInSheet=12|OwnerPartId=-1|Location.X=463|Location.Y=749|Color=8388608|FontID=1|IsHidden=T|Text=Kemet|Name=Manufacturer
|RECORD=41|OwnerIndex=853|IndexInSheet=13|OwnerPartId=-1|Location.X=463|Location.Y=749|Color=8388608|FontID=1|IsHidden=T|Text=C0603X104K5RACAUTO|Name=Part Number
|RECORD=34|OwnerIndex=853|IndexInSheet=-1|OwnerPartId=-1|Location.X=481|Location.Y=728|Color=8388608|FontID=1|Text=C2|Name=Designator|ReadOnlyState=1
|RECORD=41|OwnerIndex=853|IndexInSheet=-1|OwnerPartId=-1|Location.X=481|Location.Y=718|Color=8388608|FontID=1|Text=0.1uF|Name=Comment
|RECORD=44|OwnerIndex=853
|RECORD=45|OwnerIndex=874|IndexInSheet=-1|Description=Chip Capacitor, 2-Leads, Body 1.60x0.80mm, IPC Low Density|UseComponentLibrary=T|ModelName=CAPC1608X87X45ML20T05|ModelType=PCBLIB|DatafileCount=1|ModelDatafileEntity0=CAPC1608X87X45ML20T05|ModelDatafileKind0=PCBLib|IsCurrent=T|DatalinksLocked=T|DatabaseDatalinksLocked=T
|RECORD=46|OwnerIndex=875
|RECORD=48|OwnerIndex=875
|RECORD=41|OwnerIndex=877|IndexInSheet=-1|OwnerPartId=-1|Color=8388608|FontID=1|Text=2D|Name=Available Preview Images
|RECORD=45|OwnerIndex=874|IndexInSheet=-1|Description=Chip Capacitor, 2-Leads, Body 1.60x0.80mm, IPC High Density|UseComponentLibrary=T|ModelName=CAPC1608X87X45LL20T05|ModelType=PCBLIB|DatafileCount=1|ModelDatafileEntity0=CAPC1608X87X45LL20T05|ModelDatafileKind0=PCBLib|DatalinksLocked=T|DatabaseDatalinksLocked=T
|RECORD=46|OwnerIndex=879
|RECORD=48|OwnerIndex=879
|RECORD=41|OwnerIndex=881|IndexInSheet=-1|OwnerPartId=-1|Color=8388608|FontID=1|Text=2D|Name=Available Preview Images
|RECORD=45|OwnerIndex=874|IndexInSheet=-1|Description=Chip Capacitor, 2-Leads, Body 1.60x0.80mm, IPC Medium Density|UseComponentLibrary=T|ModelName=CAPC1608X87X45NL20T05|ModelType=PCBLIB|DatafileCount=1|ModelDatafileEntity0=CAPC1608X87X45NL20T05|ModelDatafileKind0=PCBLib|DatalinksLocked=T|DatabaseDatalinksLocked=T
|RECORD=46|OwnerIndex=883
|RECORD=48|OwnerIndex=883
|RECORD=41|OwnerIndex=885|IndexInSheet=-1|OwnerPartId=-1|Color=8388608|FontID=1|Text=2D|Name=Available Preview Images
|RECORD=1|LibReference=CAP|ComponentDescription=C0603X104K5RACAUTO|PartCount=2|DisplayModeCount=2|IndexInSheet=40|OwnerPartId=-1|Location.X=1070|Location.Y=790|Orientation=1|CurrentPartId=1|SourceLibraryName=Altium Content Vault|TargetFileName=*|AreaColor=11599871|Color=128|PartIDLocked=F|DesignItemId=CMP-2006-00003-1|AllPinCount=2
|RECORD=2|OwnerIndex=887|OwnerPartId=1|OwnerPartDisplayMode=1|FormalType=1|Electrical=4|PinConglomerate=35|PinLength=10|Location.X=1080|Location.Y=790|Name=1|Designator=1|PinPropagationDelay=0.000000E+000
|RECORD=2|OwnerIndex=887|OwnerPartId=1|OwnerPartDisplayMode=1|FormalType=1|Electrical=4|PinConglomerate=33|PinLength=10|Location.X=1080|Location.Y=800|Name=2|Designator=2|PinPropagationDelay=0.000000E+000
|RECORD=13|OwnerIndex=887|IsNotAccesible=T|IndexInSheet=2|OwnerPartId=1|OwnerPartDisplayMode=1|Location.X=1088|Location.Y=790|Corner.X=1072|Corner.Y=790|LineWidth=1|Color=16711680
|RECORD=13|OwnerIndex=887|IsNotAccesible=T|IndexInSheet=3|OwnerPartId=1|OwnerPartDisplayMode=1|Location.X=1080|Location.Y=794|Corner.X=1080|Corner.Y=800|LineWidth=1|Color=16711680
|RECORD=12|OwnerIndex=887|IsNotAccesible=T|IndexInSheet=4|OwnerPartId=1|OwnerPartDisplayMode=1|Location.X=1080|Location.Y=810|Radius=16|LineWidth=1|StartAngle=241.000|EndAngle=270.000|Color=16711680
|RECORD=12|OwnerIndex=887|IsNotAccesible=T|IndexInSheet=5|OwnerPartId=1|OwnerPartDisplayMode=1|Location.X=1080|Location.Y=810|Radius=16|LineWidth=1|StartAngle=270.000|EndAngle=299.000|Color=16711680
|RECORD=2|OwnerIndex=887|OwnerPartId=1|FormalType=1|Electrical=4|PinConglomerate=35|PinLength=10|Location.X=1080|Location.Y=790|Name=1|Designator=1|PinPropagationDelay=0.000000E+000
|RECORD=2|OwnerIndex=887|OwnerPartId=1|FormalType=1|Electrical=4|PinConglomerate=33|PinLength=10|Location.X=1080|Location.Y=800|Name=2|Designator=2|PinPropagationDelay=0.000000E+000
|RECORD=13|OwnerIndex=887|IsNotAccesible=T|IndexInSheet=8|OwnerPartId=1|Location.X=1072|Location.Y=797|Corner.X=1088|Corner.Y=797|LineWidth=1|Color=16711680
|RECORD=13|OwnerIndex=887|IsNotAccesible=T|IndexInSheet=9|OwnerPartId=1|Location.X=1088|Location.Y=793|Corner.X=1072|Corner.Y=793|LineWidth=1|Color=16711680
|RECORD=6|OwnerIndex=887|IsNotAccesible=T|IndexInSheet=10|OwnerPartId=1|LineWidth=1|Color=16711680|LocationCount=2|X1=1080|Y1=790|X2=1080|Y2=793
|RECORD=6|OwnerIndex=887|IsNotAccesible=T|IndexInSheet=11|OwnerPartId=1|LineWidth=1|Color=16711680|LocationCount=2|X1=1080|Y1=800|X2=1080|Y2=797
|RECORD=41|OwnerIndex=887|IndexInSheet=12|OwnerPartId=-1|Location.X=1071|Location.Y=812|Color=8388608|FontID=1|IsHidden=T|Text=Kemet|Name=Manufacturer
|RECORD=41|OwnerIndex=887|IndexInSheet=13|OwnerPartId=-1|Location.X=1071|Location.Y=812|Color=8388608|FontID=1|IsHidden=T|Text=C0603X104K5RACAUTO|Name=Part Number
|RECORD=34|OwnerIndex=887|IndexInSheet=-1|OwnerPartId=-1|Location.X=1089|Location.Y=791|Color=8388608|FontID=1|Text=C15|Name=Designator|ReadOnlyState=1
|RECORD=41|OwnerIndex=887|IndexInSheet=-1|OwnerPartId=-1|Location.X=1089|Location.Y=781|Color=8388608|FontID=1|Text=0.1uF|Name=Comment
|RECORD=44|OwnerIndex=887
|RECORD=45|OwnerIndex=908|IndexInSheet=-1|Description=Chip Capacitor, 2-Leads, Body 1.60x0.80mm, IPC Low Density|UseComponentLibrary=T|ModelName=CAPC1608X87X45ML20T05|ModelType=PCBLIB|DatafileCount=1|ModelDatafileEntity0=CAPC1608X87X45ML20T05|ModelDatafileKind0=PCBLib|IsCurrent=T|DatalinksLocked=T|DatabaseDatalinksLocked=T
|RECORD=46|OwnerIndex=909
|RECORD=48|OwnerIndex=909
|RECORD=41|OwnerIndex=911|IndexInSheet=-1|OwnerPartId=-1|Color=8388608|FontID=1|Text=2D|Name=Available Preview Images
|RECORD=45|OwnerIndex=908|IndexInSheet=-1|Description=Chip Capacitor, 2-Leads, Body 1.60x0.80mm, IPC High Density|UseComponentLibrary=T|ModelName=CAPC1608X87X45LL20T05|ModelType=PCBLIB|DatafileCount=1|ModelDatafileEntity0=CAPC1608X87X45LL20T05|ModelDatafileKind0=PCBLib|DatalinksLocked=T|DatabaseDatalinksLocked=T
|RECORD=46|OwnerIndex=913
|RECORD=48|OwnerIndex=913
|RECORD=41|OwnerIndex=915|IndexInSheet=-1|OwnerPartId=-1|Color=8388608|FontID=1|Text=2D|Name=Available Preview Images
|RECORD=45|OwnerIndex=908|IndexInSheet=-1|Description=Chip Capacitor, 2-Leads, Body 1.60x0.80mm, IPC Medium Density|UseComponentLibrary=T|ModelName=CAPC1608X87X45NL20T05|ModelType=PCBLIB|DatafileCount=1|ModelDatafileEntity0=CAPC1608X87X45NL20T05|ModelDatafileKind0=PCBLib|DatalinksLocked=T|DatabaseDatalinksLocked=T
|RECORD=46|OwnerIndex=917
|RECORD=48|OwnerIndex=917
|RECORD=41|OwnerIndex=919|IndexInSheet=-1|OwnerPartId=-1|Color=8388608|FontID=1|Text=2D|Name=Available Preview Images
|RECORD=1|LibReference=CAP|ComponentDescription=C0603X104K5RACAUTO|PartCount=2|DisplayModeCount=2|IndexInSheet=41|OwnerPartId=-1|Location.X=1120|Location.Y=790|Orientation=1|CurrentPartId=1|SourceLibraryName=Altium Content Vault|TargetFileName=*|AreaColor=11599871|Color=128|PartIDLocked=F|DesignItemId=CMP-2006-00003-1|AllPinCount=2
|RECORD=2|OwnerIndex=921|OwnerPartId=1|OwnerPartDisplayMode=1|FormalType=1|Electrical=4|PinConglomerate=35|PinLength=10|Location.X=1130|Location.Y=790|Name=1|Designator=1|PinPropagationDelay=0.000000E+000
|RECORD=2|OwnerIndex=921|OwnerPartId=1|OwnerPartDisplayMode=1|FormalType=1|Electrical=4|PinConglomerate=33|PinLength=10|Location.X=1130|Location.Y=800|Name=2|Designator=2|PinPropagationDelay=0.000000E+000
|RECORD=13|OwnerIndex=921|IsNotAccesible=T|IndexInSheet=2|OwnerPartId=1|OwnerPartDisplayMode=1|Location.X=1138|Location.Y=790|Corner.X=1122|Corner.Y=790|LineWidth=1|Color=16711680
|RECORD=13|OwnerIndex=921|IsNotAccesible=T|IndexInSheet=3|OwnerPartId=1|OwnerPartDisplayMode=1|Location.X=1130|Location.Y=794|Corner.X=1130|Corner.Y=800|LineWidth=1|Color=16711680
|RECORD=12|OwnerIndex=921|IsNotAccesible=T|IndexInSheet=4|OwnerPartId=1|OwnerPartDisplayMode=1|Location.X=1130|Location.Y=810|Radius=16|LineWidth=1|StartAngle=241.000|EndAngle=270.000|Color=16711680
|RECORD=12|OwnerIndex=921|IsNotAccesible=T|IndexInSheet=5|OwnerPartId=1|OwnerPartDisplayMode=1|Location.X=1130|Location.Y=810|Radius=16|LineWidth=1|StartAngle=270.000|EndAngle=299.000|Color=16711680
|RECORD=2|OwnerIndex=921|OwnerPartId=1|FormalType=1|Electrical=4|PinConglomerate=35|PinLength=10|Location.X=1130|Location.Y=790|Name=1|Designator=1|PinPropagationDelay=0.000000E+000
|RECORD=2|OwnerIndex=921|OwnerPartId=1|FormalType=1|Electrical=4|PinConglomerate=33|PinLength=10|Location.X=1130|Location.Y=800|Name=2|Designator=2|PinPropagationDelay=0.000000E+000
|RECORD=13|OwnerIndex=921|IsNotAccesible=T|IndexInSheet=8|OwnerPartId=1|Location.X=1122|Location.Y=797|Corner.X=1138|Corner.Y=797|LineWidth=1|Color=16711680
|RECORD=13|OwnerIndex=921|IsNotAccesible=T|IndexInSheet=9|OwnerPartId=1|Location.X=1138|Location.Y=793|Corner.X=1122|Corner.Y=793|LineWidth=1|Color=16711680
|RECORD=6|OwnerIndex=921|IsNotAccesible=T|IndexInSheet=10|OwnerPartId=1|LineWidth=1|Color=16711680|LocationCount=2|X1=1130|Y1=790|X2=1130|Y2=793
|RECORD=6|OwnerIndex=921|IsNotAccesible=T|IndexInSheet=11|OwnerPartId=1|LineWidth=1|Color=16711680|LocationCount=2|X1=1130|Y1=800|X2=1130|Y2=797
|RECORD=41|OwnerIndex=921|IndexInSheet=12|OwnerPartId=-1|Location.X=1121|Location.Y=812|Color=8388608|FontID=1|IsHidden=T|Text=Kemet|Name=Manufacturer
|RECORD=41|OwnerIndex=921|IndexInSheet=13|OwnerPartId=-1|Location.X=1121|Location.Y=812|Color=8388608|FontID=1|IsHidden=T|Text=C0603X104K5RACAUTO|Name=Part Number
|RECORD=34|OwnerIndex=921|IndexInSheet=-1|OwnerPartId=-1|Location.X=1139|Location.Y=791|Color=8388608|FontID=1|Text=C16|Name=Designator|ReadOnlyState=1
|RECORD=41|OwnerIndex=921|IndexInSheet=-1|OwnerPartId=-1|Location.X=1139|Location.Y=781|Color=8388608|FontID=1|Text=0.1uF|Name=Comment
|RECORD=44|OwnerIndex=921
|RECORD=45|OwnerIndex=942|IndexInSheet=-1|Description=Chip Capacitor, 2-Leads, Body 1.60x0.80mm, IPC Low Density|UseComponentLibrary=T|ModelName=CAPC1608X87X45ML20T05|ModelType=PCBLIB|DatafileCount=1|ModelDatafileEntity0=CAPC1608X87X45ML20T05|ModelDatafileKind0=PCBLib|IsCurrent=T|DatalinksLocked=T|DatabaseDatalinksLocked=T
|RECORD=46|OwnerIndex=943
|RECORD=48|OwnerIndex=943
|RECORD=41|OwnerIndex=945|IndexInSheet=-1|OwnerPartId=-1|Color=8388608|FontID=1|Text=2D|Name=Available Preview Images
|RECORD=45|OwnerIndex=942|IndexInSheet=-1|Description=Chip Capacitor, 2-Leads, Body 1.60x0.80mm, IPC High Density|UseComponentLibrary=T|ModelName=CAPC1608X87X45LL20T05|ModelType=PCBLIB|DatafileCount=1|ModelDatafileEntity0=CAPC1608X87X45LL20T05|ModelDatafileKind0=PCBLib|DatalinksLocked=T|DatabaseDatalinksLocked=T
|RECORD=46|OwnerIndex=947
|RECORD=48|OwnerIndex=947
|RECORD=41|OwnerIndex=949|IndexInSheet=-1|OwnerPartId=-1|Color=8388608|FontID=1|Text=2D|Name=Available Preview Images
|RECORD=45|OwnerIndex=942|IndexInSheet=-1|Description=Chip Capacitor, 2-Leads, Body 1.60x0.80mm, IPC Medium Density|UseComponentLibrary=T|ModelName=CAPC1608X87X45NL20T05|ModelType=PCBLIB|DatafileCount=1|ModelDatafileEntity0=CAPC1608X87X45NL20T05|ModelDatafileKind0=PCBLib|DatalinksLocked=T|DatabaseDatalinksLocked=T
|RECORD=46|OwnerIndex=951
|RECORD=48|OwnerIndex=951
|RECORD=41|OwnerIndex=953|IndexInSheet=-1|OwnerPartId=-1|Color=8388608|FontID=1|Text=2D|Name=Available Preview Images
|RECORD=1|LibReference=CAP|ComponentDescription=C0603X104K5RACAUTO|PartCount=2|DisplayModeCount=2|IndexInSheet=42|OwnerPartId=-1|Location.X=1170|Location.Y=790|Orientation=1|CurrentPartId=1|SourceLibraryName=Altium Content Vault|TargetFileName=*|AreaColor=11599871|Color=128|PartIDLocked=F|DesignItemId=CMP-2006-00003-1|AllPinCount=2
|RECORD=2|OwnerIndex=955|OwnerPartId=1|OwnerPartDisplayMode=1|FormalType=1|Electrical=4|PinConglomerate=35|PinLength=10|Location.X=1180|Location.Y=790|Name=1|Designator=1|PinPropagationDelay=0.000000E+000
|RECORD=2|OwnerIndex=955|OwnerPartId=1|OwnerPartDisplayMode=1|FormalType=1|Electrical=4|PinConglomerate=33|PinLength=10|Location.X=1180|Location.Y=800|Name=2|Designator=2|PinPropagationDelay=0.000000E+000
|RECORD=13|OwnerIndex=955|IsNotAccesible=T|IndexInSheet=2|OwnerPartId=1|OwnerPartDisplayMode=1|Location.X=1188|Location.Y=790|Corner.X=1172|Corner.Y=790|LineWidth=1|Color=16711680
|RECORD=13|OwnerIndex=955|IsNotAccesible=T|IndexInSheet=3|OwnerPartId=1|OwnerPartDisplayMode=1|Location.X=1180|Location.Y=794|Corner.X=1180|Corner.Y=800|LineWidth=1|Color=16711680
|RECORD=12|OwnerIndex=955|IsNotAccesible=T|IndexInSheet=4|OwnerPartId=1|OwnerPartDisplayMode=1|Location.X=1180|Location.Y=810|Radius=16|LineWidth=1|StartAngle=241.000|EndAngle=270.000|Color=16711680
|RECORD=12|OwnerIndex=955|IsNotAccesible=T|IndexInSheet=5|OwnerPartId=1|OwnerPartDisplayMode=1|Location.X=1180|Location.Y=810|Radius=16|LineWidth=1|StartAngle=270.000|EndAngle=299.000|Color=16711680
|RECORD=2|OwnerIndex=955|OwnerPartId=1|FormalType=1|Electrical=4|PinConglomerate=35|PinLength=10|Location.X=1180|Location.Y=790|Name=1|Designator=1|PinPropagationDelay=0.000000E+000
|RECORD=2|OwnerIndex=955|OwnerPartId=1|FormalType=1|Electrical=4|PinConglomerate=33|PinLength=10|Location.X=1180|Location.Y=800|Name=2|Designator=2|PinPropagationDelay=0.000000E+000
|RECORD=13|OwnerIndex=955|IsNotAccesible=T|IndexInSheet=8|OwnerPartId=1|Location.X=1172|Location.Y=797|Corner.X=1188|Corner.Y=797|LineWidth=1|Color=16711680
|RECORD=13|OwnerIndex=955|IsNotAccesible=T|IndexInSheet=9|OwnerPartId=1|Location.X=1188|Location.Y=793|Corner.X=1172|Corner.Y=793|LineWidth=1|Color=16711680
|RECORD=6|OwnerIndex=955|IsNotAccesible=T|IndexInSheet=10|OwnerPartId=1|LineWidth=1|Color=16711680|LocationCount=2|X1=1180|Y1=790|X2=1180|Y2=793
|RECORD=6|OwnerIndex=955|IsNotAccesible=T|IndexInSheet=11|OwnerPartId=1|LineWidth=1|Color=16711680|LocationCount=2|X1=1180|Y1=800|X2=1180|Y2=797
|RECORD=41|OwnerIndex=955|IndexInSheet=12|OwnerPartId=-1|Location.X=1171|Location.Y=812|Color=8388608|FontID=1|IsHidden=T|Text=Kemet|Name=Manufacturer
|RECORD=41|OwnerIndex=955|IndexInSheet=13|OwnerPartId=-1|Location.X=1171|Location.Y=812|Color=8388608|FontID=1|IsHidden=T|Text=C0603X104K5RACAUTO|Name=Part Number
|RECORD=34|OwnerIndex=955|IndexInSheet=-1|OwnerPartId=-1|Location.X=1189|Location.Y=791|Color=8388608|FontID=1|Text=C17|Name=Designator|ReadOnlyState=1
|RECORD=41|OwnerIndex=955|IndexInSheet=-1|OwnerPartId=-1|Location.X=1189|Location.Y=781|Color=8388608|FontID=1|Text=0.1uF|Name=Comment
|RECORD=44|OwnerIndex=955
|RECORD=45|OwnerIndex=976|IndexInSheet=-1|Description=Chip Capacitor, 2-Leads, Body 1.60x0.80mm, IPC Low Density|UseComponentLibrary=T|ModelName=CAPC1608X87X45ML20T05|ModelType=PCBLIB|DatafileCount=1|ModelDatafileEntity0=CAPC1608X87X45ML20T05|ModelDatafileKind0=PCBLib|IsCurrent=T|DatalinksLocked=T|DatabaseDatalinksLocked=T
|RECORD=46|OwnerIndex=977
|RECORD=48|OwnerIndex=977
|RECORD=41|OwnerIndex=979|IndexInSheet=-1|OwnerPartId=-1|Color=8388608|FontID=1|Text=2D|Name=Available Preview Images
|RECORD=45|OwnerIndex=976|IndexInSheet=-1|Description=Chip Capacitor, 2-Leads, Body 1.60x0.80mm, IPC High Density|UseComponentLibrary=T|ModelName=CAPC1608X87X45LL20T05|ModelType=PCBLIB|DatafileCount=1|ModelDatafileEntity0=CAPC1608X87X45LL20T05|ModelDatafileKind0=PCBLib|DatalinksLocked=T|DatabaseDatalinksLocked=T
|RECORD=46|OwnerIndex=981
|RECORD=48|OwnerIndex=981
|RECORD=41|OwnerIndex=983|IndexInSheet=-1|OwnerPartId=-1|Color=8388608|FontID=1|Text=2D|Name=Available Preview Images
|RECORD=45|OwnerIndex=976|IndexInSheet=-1|Description=Chip Capacitor, 2-Leads, Body 1.60x0.80mm, IPC Medium Density|UseComponentLibrary=T|ModelName=CAPC1608X87X45NL20T05|ModelType=PCBLIB|DatafileCount=1|ModelDatafileEntity0=CAPC1608X87X45NL20T05|ModelDatafileKind0=PCBLib|DatalinksLocked=T|DatabaseDatalinksLocked=T
|RECORD=46|OwnerIndex=985
|RECORD=48|OwnerIndex=985
|RECORD=41|OwnerIndex=987|IndexInSheet=-1|OwnerPartId=-1|Color=8388608|FontID=1|Text=2D|Name=Available Preview Images
|RECORD=1|LibReference=CAP|ComponentDescription=C0603X104K5RACAUTO|PartCount=2|DisplayModeCount=2|IndexInSheet=43|OwnerPartId=-1|Location.X=1220|Location.Y=790|Orientation=1|CurrentPartId=1|SourceLibraryName=Altium Content Vault|TargetFileName=*|AreaColor=11599871|Color=128|PartIDLocked=F|DesignItemId=CMP-2006-00003-1|AllPinCount=2
|RECORD=2|OwnerIndex=989|OwnerPartId=1|OwnerPartDisplayMode=1|FormalType=1|Electrical=4|PinConglomerate=35|PinLength=10|Location.X=1230|Location.Y=790|Name=1|Designator=1|PinPropagationDelay=0.000000E+000
|RECORD=2|OwnerIndex=989|OwnerPartId=1|OwnerPartDisplayMode=1|FormalType=1|Electrical=4|PinConglomerate=33|PinLength=10|Location.X=1230|Location.Y=800|Name=2|Designator=2|PinPropagationDelay=0.000000E+000
|RECORD=13|OwnerIndex=989|IsNotAccesible=T|IndexInSheet=2|OwnerPartId=1|OwnerPartDisplayMode=1|Location.X=1238|Location.Y=790|Corner.X=1222|Corner.Y=790|LineWidth=1|Color=16711680
|RECORD=13|OwnerIndex=989|IsNotAccesible=T|IndexInSheet=3|OwnerPartId=1|OwnerPartDisplayMode=1|Location.X=1230|Location.Y=794|Corner.X=1230|Corner.Y=800|LineWidth=1|Color=16711680
|RECORD=12|OwnerIndex=989|IsNotAccesible=T|IndexInSheet=4|OwnerPartId=1|OwnerPartDisplayMode=1|Location.X=1230|Location.Y=810|Radius=16|LineWidth=1|StartAngle=241.000|EndAngle=270.000|Color=16711680
|RECORD=12|OwnerIndex=989|IsNotAccesible=T|IndexInSheet=5|OwnerPartId=1|OwnerPartDisplayMode=1|Location.X=1230|Location.Y=810|Radius=16|LineWidth=1|StartAngle=270.000|EndAngle=299.000|Color=16711680
|RECORD=2|OwnerIndex=989|OwnerPartId=1|FormalType=1|Electrical=4|PinConglomerate=35|PinLength=10|Location.X=1230|Location.Y=790|Name=1|Designator=1|PinPropagationDelay=0.000000E+000
|RECORD=2|OwnerIndex=989|OwnerPartId=1|FormalType=1|Electrical=4|PinConglomerate=33|PinLength=10|Location.X=1230|Location.Y=800|Name=2|Designator=2|PinPropagationDelay=0.000000E+000
|RECORD=13|OwnerIndex=989|IsNotAccesible=T|IndexInSheet=8|OwnerPartId=1|Location.X=1222|Location.Y=797|Corner.X=1238|Corner.Y=797|LineWidth=1|Color=16711680
|RECORD=13|OwnerIndex=989|IsNotAccesible=T|IndexInSheet=9|OwnerPartId=1|Location.X=1238|Location.Y=793|Corner.X=1222|Corner.Y=793|LineWidth=1|Color=16711680
|RECORD=6|OwnerIndex=989|IsNotAccesible=T|IndexInSheet=10|OwnerPartId=1|LineWidth=1|Color=16711680|LocationCount=2|X1=1230|Y1=790|X2=1230|Y2=793
|RECORD=6|OwnerIndex=989|IsNotAccesible=T|IndexInSheet=11|OwnerPartId=1|LineWidth=1|Color=16711680|LocationCount=2|X1=1230|Y1=800|X2=1230|Y2=797
|RECORD=41|OwnerIndex=989|IndexInSheet=12|OwnerPartId=-1|Location.X=1221|Location.Y=812|Color=8388608|FontID=1|IsHidden=T|Text=Kemet|Name=Manufacturer
|RECORD=41|OwnerIndex=989|IndexInSheet=13|OwnerPartId=-1|Location.X=1221|Location.Y=812|Color=8388608|FontID=1|IsHidden=T|Text=C0603X104K5RACAUTO|Name=Part Number
|RECORD=34|OwnerIndex=989|IndexInSheet=-1|OwnerPartId=-1|Location.X=1239|Location.Y=791|Color=8388608|FontID=1|Text=C18|Name=Designator|ReadOnlyState=1
|RECORD=41|OwnerIndex=989|IndexInSheet=-1|OwnerPartId=-1|Location.X=1239|Location.Y=781|Color=8388608|FontID=1|Text=0.1uF|Name=Comment
|RECORD=44|OwnerIndex=989
|RECORD=45|OwnerIndex=1010|IndexInSheet=-1|Description=Chip Capacitor, 2-Leads, Body 1.60x0.80mm, IPC Low Density|UseComponentLibrary=T|ModelName=CAPC1608X87X45ML20T05|ModelType=PCBLIB|DatafileCount=1|ModelDatafileEntity0=CAPC1608X87X45ML20T05|ModelDatafileKind0=PCBLib|IsCurrent=T|DatalinksLocked=T|DatabaseDatalinksLocked=T
|RECORD=46|OwnerIndex=1011
|RECORD=48|OwnerIndex=1011
|RECORD=41|OwnerIndex=1013|IndexInSheet=-1|OwnerPartId=-1|Color=8388608|FontID=1|Text=2D|Name=Available Preview Images
|RECORD=45|OwnerIndex=1010|IndexInSheet=-1|Description=Chip Capacitor, 2-Leads, Body 1.60x0.80mm, IPC High Density|UseComponentLibrary=T|ModelName=CAPC1608X87X45LL20T05|ModelType=PCBLIB|DatafileCount=1|ModelDatafileEntity0=CAPC1608X87X45LL20T05|ModelDatafileKind0=PCBLib|DatalinksLocked=T|DatabaseDatalinksLocked=T
|RECORD=46|OwnerIndex=1015
|RECORD=48|OwnerIndex=1015
|RECORD=41|OwnerIndex=1017|IndexInSheet=-1|OwnerPartId=-1|Color=8388608|FontID=1|Text=2D|Name=Available Preview Images
|RECORD=45|OwnerIndex=1010|IndexInSheet=-1|Description=Chip Capacitor, 2-Leads, Body 1.60x0.80mm, IPC Medium Density|UseComponentLibrary=T|ModelName=CAPC1608X87X45NL20T05|ModelType=PCBLIB|DatafileCount=1|ModelDatafileEntity0=CAPC1608X87X45NL20T05|ModelDatafileKind0=PCBLib|DatalinksLocked=T|DatabaseDatalinksLocked=T
|RECORD=46|OwnerIndex=1019
|RECORD=48|OwnerIndex=1019
|RECORD=41|OwnerIndex=1021|IndexInSheet=-1|OwnerPartId=-1|Color=8388608|FontID=1|Text=2D|Name=Available Preview Images
|RECORD=1|LibReference=CAP|ComponentDescription=C0603X104K5RACAUTO|PartCount=2|DisplayModeCount=2|IndexInSheet=44|OwnerPartId=-1|Location.X=570|Location.Y=780|Orientation=1|CurrentPartId=1|SourceLibraryName=Altium Content Vault|TargetFileName=*|AreaColor=11599871|Color=128|PartIDLocked=F|DesignItemId=CMP-2006-00003-1|AllPinCount=2
|RECORD=2|OwnerIndex=1023|OwnerPartId=1|OwnerPartDisplayMode=1|FormalType=1|Electrical=4|PinConglomerate=35|PinLength=10|Location.X=580|Location.Y=780|Name=1|Designator=1|PinPropagationDelay=0.000000E+000
|RECORD=2|OwnerIndex=1023|OwnerPartId=1|OwnerPartDisplayMode=1|FormalType=1|Electrical=4|PinConglomerate=33|PinLength=10|Location.X=580|Location.Y=790|Name=2|Designator=2|PinPropagationDelay=0.000000E+000
|RECORD=13|OwnerIndex=1023|IsNotAccesible=T|IndexInSheet=2|OwnerPartId=1|OwnerPartDisplayMode=1|Location.X=588|Location.Y=780|Corner.X=572|Corner.Y=780|LineWidth=1|Color=16711680
|RECORD=13|OwnerIndex=1023|IsNotAccesible=T|IndexInSheet=3|OwnerPartId=1|OwnerPartDisplayMode=1|Location.X=580|Location.Y=784|Corner.X=580|Corner.Y=790|LineWidth=1|Color=16711680
|RECORD=12|OwnerIndex=1023|IsNotAccesible=T|IndexInSheet=4|OwnerPartId=1|OwnerPartDisplayMode=1|Location.X=580|Location.Y=800|Radius=16|LineWidth=1|StartAngle=241.000|EndAngle=270.000|Color=16711680
|RECORD=12|OwnerIndex=1023|IsNotAccesible=T|IndexInSheet=5|OwnerPartId=1|OwnerPartDisplayMode=1|Location.X=580|Location.Y=800|Radius=16|LineWidth=1|StartAngle=270.000|EndAngle=299.000|Color=16711680
|RECORD=2|OwnerIndex=1023|OwnerPartId=1|FormalType=1|Electrical=4|PinConglomerate=35|PinLength=10|Location.X=580|Location.Y=780|Name=1|Designator=1|PinPropagationDelay=0.000000E+000
|RECORD=2|OwnerIndex=1023|OwnerPartId=1|FormalType=1|Electrical=4|PinConglomerate=33|PinLength=10|Location.X=580|Location.Y=790|Name=2|Designator=2|PinPropagationDelay=0.000000E+000
|RECORD=13|OwnerIndex=1023|IsNotAccesible=T|IndexInSheet=8|OwnerPartId=1|Location.X=572|Location.Y=787|Corner.X=588|Corner.Y=787|LineWidth=1|Color=16711680
|RECORD=13|OwnerIndex=1023|IsNotAccesible=T|IndexInSheet=9|OwnerPartId=1|Location.X=588|Location.Y=783|Corner.X=572|Corner.Y=783|LineWidth=1|Color=16711680
|RECORD=6|OwnerIndex=1023|IsNotAccesible=T|IndexInSheet=10|OwnerPartId=1|LineWidth=1|Color=16711680|LocationCount=2|X1=580|Y1=780|X2=580|Y2=783
|RECORD=6|OwnerIndex=1023|IsNotAccesible=T|IndexInSheet=11|OwnerPartId=1|LineWidth=1|Color=16711680|LocationCount=2|X1=580|Y1=790|X2=580|Y2=787
|RECORD=41|OwnerIndex=1023|IndexInSheet=12|OwnerPartId=-1|Location.X=571|Location.Y=802|Color=8388608|FontID=1|IsHidden=T|Text=Kemet|Name=Manufacturer
|RECORD=41|OwnerIndex=1023|IndexInSheet=13|OwnerPartId=-1|Location.X=571|Location.Y=802|Color=8388608|FontID=1|IsHidden=T|Text=C0603X104K5RACAUTO|Name=Part Number
|RECORD=34|OwnerIndex=1023|IndexInSheet=-1|OwnerPartId=-1|Location.X=589|Location.Y=781|Color=8388608|FontID=1|Text=C19|Name=Designator|ReadOnlyState=1
|RECORD=41|OwnerIndex=1023|IndexInSheet=-1|OwnerPartId=-1|Location.X=589|Location.Y=771|Color=8388608|FontID=1|Text=0.1uF|Name=Comment
|RECORD=44|OwnerIndex=1023
|RECORD=45|OwnerIndex=1044|IndexInSheet=-1|Description=Chip Capacitor, 2-Leads, Body 1.60x0.80mm, IPC Low Density|UseComponentLibrary=T|ModelName=CAPC1608X87X45ML20T05|ModelType=PCBLIB|DatafileCount=1|ModelDatafileEntity0=CAPC1608X87X45ML20T05|ModelDatafileKind0=PCBLib|IsCurrent=T|DatalinksLocked=T|DatabaseDatalinksLocked=T
|RECORD=46|OwnerIndex=1045
|RECORD=48|OwnerIndex=1045
|RECORD=41|OwnerIndex=1047|IndexInSheet=-1|OwnerPartId=-1|Color=8388608|FontID=1|Text=2D|Name=Available Preview Images
|RECORD=45|OwnerIndex=1044|IndexInSheet=-1|Description=Chip Capacitor, 2-Leads, Body 1.60x0.80mm, IPC High Density|UseComponentLibrary=T|ModelName=CAPC1608X87X45LL20T05|ModelType=PCBLIB|DatafileCount=1|ModelDatafileEntity0=CAPC1608X87X45LL20T05|ModelDatafileKind0=PCBLib|DatalinksLocked=T|DatabaseDatalinksLocked=T
|RECORD=46|OwnerIndex=1049
|RECORD=48|OwnerIndex=1049
|RECORD=41|OwnerIndex=1051|IndexInSheet=-1|OwnerPartId=-1|Color=8388608|FontID=1|Text=2D|Name=Available Preview Images
|RECORD=45|OwnerIndex=1044|IndexInSheet=-1|Description=Chip Capacitor, 2-Leads, Body 1.60x0.80mm, IPC Medium Density|UseComponentLibrary=T|ModelName=CAPC1608X87X45NL20T05|ModelType=PCBLIB|DatafileCount=1|ModelDatafileEntity0=CAPC1608X87X45NL20T05|ModelDatafileKind0=PCBLib|DatalinksLocked=T|DatabaseDatalinksLocked=T
|RECORD=46|OwnerIndex=1053
|RECORD=48|OwnerIndex=1053
|RECORD=41|OwnerIndex=1055|IndexInSheet=-1|OwnerPartId=-1|Color=8388608|FontID=1|Text=2D|Name=Available Preview Images
|RECORD=1|LibReference=CAP|ComponentDescription=C0603X104K5RACAUTO|PartCount=2|DisplayModeCount=2|IndexInSheet=45|OwnerPartId=-1|Location.X=580|Location.Y=340|Orientation=1|CurrentPartId=1|SourceLibraryName=Altium Content Vault|TargetFileName=*|AreaColor=11599871|Color=128|PartIDLocked=F|DesignItemId=CMP-2006-00003-1|AllPinCount=2
|RECORD=2|OwnerIndex=1057|OwnerPartId=1|OwnerPartDisplayMode=1|FormalType=1|Electrical=4|PinConglomerate=35|PinLength=10|Location.X=590|Location.Y=340|Name=1|Designator=1|PinPropagationDelay=0.000000E+000
|RECORD=2|OwnerIndex=1057|OwnerPartId=1|OwnerPartDisplayMode=1|FormalType=1|Electrical=4|PinConglomerate=33|PinLength=10|Location.X=590|Location.Y=350|Name=2|Designator=2|PinPropagationDelay=0.000000E+000
|RECORD=13|OwnerIndex=1057|IsNotAccesible=T|IndexInSheet=2|OwnerPartId=1|OwnerPartDisplayMode=1|Location.X=598|Location.Y=340|Corner.X=582|Corner.Y=340|LineWidth=1|Color=16711680
|RECORD=13|OwnerIndex=1057|IsNotAccesible=T|IndexInSheet=3|OwnerPartId=1|OwnerPartDisplayMode=1|Location.X=590|Location.Y=344|Corner.X=590|Corner.Y=350|LineWidth=1|Color=16711680
|RECORD=12|OwnerIndex=1057|IsNotAccesible=T|IndexInSheet=4|OwnerPartId=1|OwnerPartDisplayMode=1|Location.X=590|Location.Y=360|Radius=16|LineWidth=1|StartAngle=241.000|EndAngle=270.000|Color=16711680
|RECORD=12|OwnerIndex=1057|IsNotAccesible=T|IndexInSheet=5|OwnerPartId=1|OwnerPartDisplayMode=1|Location.X=590|Location.Y=360|Radius=16|LineWidth=1|StartAngle=270.000|EndAngle=299.000|Color=16711680
|RECORD=2|OwnerIndex=1057|OwnerPartId=1|FormalType=1|Electrical=4|PinConglomerate=35|PinLength=10|Location.X=590|Location.Y=340|Name=1|Designator=1|PinPropagationDelay=0.000000E+000
|RECORD=2|OwnerIndex=1057|OwnerPartId=1|FormalType=1|Electrical=4|PinConglomerate=33|PinLength=10|Location.X=590|Location.Y=350|Name=2|Designator=2|PinPropagationDelay=0.000000E+000
|RECORD=13|OwnerIndex=1057|IsNotAccesible=T|IndexInSheet=8|OwnerPartId=1|Location.X=582|Location.Y=347|Corner.X=598|Corner.Y=347|LineWidth=1|Color=16711680
|RECORD=13|OwnerIndex=1057|IsNotAccesible=T|IndexInSheet=9|OwnerPartId=1|Location.X=598|Location.Y=343|Corner.X=582|Corner.Y=343|LineWidth=1|Color=16711680
|RECORD=6|OwnerIndex=1057|IsNotAccesible=T|IndexInSheet=10|OwnerPartId=1|LineWidth=1|Color=16711680|LocationCount=2|X1=590|Y1=340|X2=590|Y2=343
|RECORD=6|OwnerIndex=1057|IsNotAccesible=T|IndexInSheet=11|OwnerPartId=1|LineWidth=1|Color=16711680|LocationCount=2|X1=590|Y1=350|X2=590|Y2=347
|RECORD=41|OwnerIndex=1057|IndexInSheet=12|OwnerPartId=-1|Location.X=581|Location.Y=362|Color=8388608|FontID=1|IsHidden=T|Text=Kemet|Name=Manufacturer
|RECORD=41|OwnerIndex=1057|IndexInSheet=13|OwnerPartId=-1|Location.X=581|Location.Y=362|Color=8388608|FontID=1|IsHidden=T|Text=C0603X104K5RACAUTO|Name=Part Number
|RECORD=34|OwnerIndex=1057|IndexInSheet=-1|OwnerPartId=-1|Location.X=599|Location.Y=341|Color=8388608|FontID=1|Text=C21|Name=Designator|ReadOnlyState=1
|RECORD=41|OwnerIndex=1057|IndexInSheet=-1|OwnerPartId=-1|Location.X=599|Location.Y=331|Color=8388608|FontID=1|Text=0.1uF|Name=Comment
|RECORD=44|OwnerIndex=1057
|RECORD=45|OwnerIndex=1078|IndexInSheet=-1|Description=Chip Capacitor, 2-Leads, Body 1.60x0.80mm, IPC Low Density|UseComponentLibrary=T|ModelName=CAPC1608X87X45ML20T05|ModelType=PCBLIB|DatafileCount=1|ModelDatafileEntity0=CAPC1608X87X45ML20T05|ModelDatafileKind0=PCBLib|IsCurrent=T|DatalinksLocked=T|DatabaseDatalinksLocked=T
|RECORD=46|OwnerIndex=1079
|RECORD=48|OwnerIndex=1079
|RECORD=41|OwnerIndex=1081|IndexInSheet=-1|OwnerPartId=-1|Color=8388608|FontID=1|Text=2D|Name=Available Preview Images
|RECORD=45|OwnerIndex=1078|IndexInSheet=-1|Description=Chip Capacitor, 2-Leads, Body 1.60x0.80mm, IPC High Density|UseComponentLibrary=T|ModelName=CAPC1608X87X45LL20T05|ModelType=PCBLIB|DatafileCount=1|ModelDatafileEntity0=CAPC1608X87X45LL20T05|ModelDatafileKind0=PCBLib|DatalinksLocked=T|DatabaseDatalinksLocked=T
|RECORD=46|OwnerIndex=1083
|RECORD=48|OwnerIndex=1083
|RECORD=41|OwnerIndex=1085|IndexInSheet=-1|OwnerPartId=-1|Color=8388608|FontID=1|Text=2D|Name=Available Preview Images
|RECORD=45|OwnerIndex=1078|IndexInSheet=-1|Description=Chip Capacitor, 2-Leads, Body 1.60x0.80mm, IPC Medium Density|UseComponentLibrary=T|ModelName=CAPC1608X87X45NL20T05|ModelType=PCBLIB|DatafileCount=1|ModelDatafileEntity0=CAPC1608X87X45NL20T05|ModelDatafileKind0=PCBLib|DatalinksLocked=T|DatabaseDatalinksLocked=T
|RECORD=46|OwnerIndex=1087
|RECORD=48|OwnerIndex=1087
|RECORD=41|OwnerIndex=1089|IndexInSheet=-1|OwnerPartId=-1|Color=8388608|FontID=1|Text=2D|Name=Available Preview Images
|RECORD=1|LibReference=CAP|ComponentDescription=C0603X104K5RACAUTO|PartCount=2|DisplayModeCount=2|IndexInSheet=46|OwnerPartId=-1|Location.X=1060|Location.Y=390|Orientation=1|CurrentPartId=1|SourceLibraryName=Altium Content Vault|TargetFileName=*|AreaColor=11599871|Color=128|PartIDLocked=F|DesignItemId=CMP-2006-00003-1|AllPinCount=2
|RECORD=2|OwnerIndex=1091|OwnerPartId=1|OwnerPartDisplayMode=1|FormalType=1|Electrical=4|PinConglomerate=35|PinLength=10|Location.X=1070|Location.Y=390|Name=1|Designator=1|PinPropagationDelay=0.000000E+000
|RECORD=2|OwnerIndex=1091|OwnerPartId=1|OwnerPartDisplayMode=1|FormalType=1|Electrical=4|PinConglomerate=33|PinLength=10|Location.X=1070|Location.Y=400|Name=2|Designator=2|PinPropagationDelay=0.000000E+000
|RECORD=13|OwnerIndex=1091|IsNotAccesible=T|IndexInSheet=2|OwnerPartId=1|OwnerPartDisplayMode=1|Location.X=1078|Location.Y=390|Corner.X=1062|Corner.Y=390|LineWidth=1|Color=16711680
|RECORD=13|OwnerIndex=1091|IsNotAccesible=T|IndexInSheet=3|OwnerPartId=1|OwnerPartDisplayMode=1|Location.X=1070|Location.Y=394|Corner.X=1070|Corner.Y=400|LineWidth=1|Color=16711680
|RECORD=12|OwnerIndex=1091|IsNotAccesible=T|IndexInSheet=4|OwnerPartId=1|OwnerPartDisplayMode=1|Location.X=1070|Location.Y=410|Radius=16|LineWidth=1|StartAngle=241.000|EndAngle=270.000|Color=16711680
|RECORD=12|OwnerIndex=1091|IsNotAccesible=T|IndexInSheet=5|OwnerPartId=1|OwnerPartDisplayMode=1|Location.X=1070|Location.Y=410|Radius=16|LineWidth=1|StartAngle=270.000|EndAngle=299.000|Color=16711680
|RECORD=2|OwnerIndex=1091|OwnerPartId=1|FormalType=1|Electrical=4|PinConglomerate=35|PinLength=10|Location.X=1070|Location.Y=390|Name=1|Designator=1|PinPropagationDelay=0.000000E+000
|RECORD=2|OwnerIndex=1091|OwnerPartId=1|FormalType=1|Electrical=4|PinConglomerate=33|PinLength=10|Location.X=1070|Location.Y=400|Name=2|Designator=2|PinPropagationDelay=0.000000E+000
|RECORD=13|OwnerIndex=1091|IsNotAccesible=T|IndexInSheet=8|OwnerPartId=1|Location.X=1062|Location.Y=397|Corner.X=1078|Corner.Y=397|LineWidth=1|Color=16711680
|RECORD=13|OwnerIndex=1091|IsNotAccesible=T|IndexInSheet=9|OwnerPartId=1|Location.X=1078|Location.Y=393|Corner.X=1062|Corner.Y=393|LineWidth=1|Color=16711680
|RECORD=6|OwnerIndex=1091|IsNotAccesible=T|IndexInSheet=10|OwnerPartId=1|LineWidth=1|Color=16711680|LocationCount=2|X1=1070|Y1=390|X2=1070|Y2=393
|RECORD=6|OwnerIndex=1091|IsNotAccesible=T|IndexInSheet=11|OwnerPartId=1|LineWidth=1|Color=16711680|LocationCount=2|X1=1070|Y1=400|X2=1070|Y2=397
|RECORD=41|OwnerIndex=1091|IndexInSheet=12|OwnerPartId=-1|Location.X=1061|Location.Y=412|Color=8388608|FontID=1|IsHidden=T|Text=Kemet|Name=Manufacturer
|RECORD=41|OwnerIndex=1091|IndexInSheet=13|OwnerPartId=-1|Location.X=1061|Location.Y=412|Color=8388608|FontID=1|IsHidden=T|Text=C0603X104K5RACAUTO|Name=Part Number
|RECORD=34|OwnerIndex=1091|IndexInSheet=-1|OwnerPartId=-1|Location.X=1079|Location.Y=391|Color=8388608|FontID=1|Text=C9|Name=Designator|ReadOnlyState=1
|RECORD=41|OwnerIndex=1091|IndexInSheet=-1|OwnerPartId=-1|Location.X=1080|Location.Y=380|Color=8388608|FontID=1|Text=0.1uF|Name=Comment
|RECORD=44|OwnerIndex=1091
|RECORD=45|OwnerIndex=1112|IndexInSheet=-1|Description=Chip Capacitor, 2-Leads, Body 1.60x0.80mm, IPC Low Density|UseComponentLibrary=T|ModelName=CAPC1608X87X45ML20T05|ModelType=PCBLIB|DatafileCount=1|ModelDatafileEntity0=CAPC1608X87X45ML20T05|ModelDatafileKind0=PCBLib|IsCurrent=T|DatalinksLocked=T|DatabaseDatalinksLocked=T
|RECORD=46|OwnerIndex=1113
|RECORD=48|OwnerIndex=1113
|RECORD=41|OwnerIndex=1115|IndexInSheet=-1|OwnerPartId=-1|Color=8388608|FontID=1|Text=2D|Name=Available Preview Images
|RECORD=45|OwnerIndex=1112|IndexInSheet=-1|Description=Chip Capacitor, 2-Leads, Body 1.60x0.80mm, IPC High Density|UseComponentLibrary=T|ModelName=CAPC1608X87X45LL20T05|ModelType=PCBLIB|DatafileCount=1|ModelDatafileEntity0=CAPC1608X87X45LL20T05|ModelDatafileKind0=PCBLib|DatalinksLocked=T|DatabaseDatalinksLocked=T
|RECORD=46|OwnerIndex=1117
|RECORD=48|OwnerIndex=1117
|RECORD=41|OwnerIndex=1119|IndexInSheet=-1|OwnerPartId=-1|Color=8388608|FontID=1|Text=2D|Name=Available Preview Images
|RECORD=45|OwnerIndex=1112|IndexInSheet=-1|Description=Chip Capacitor, 2-Leads, Body 1.60x0.80mm, IPC Medium Density|UseComponentLibrary=T|ModelName=CAPC1608X87X45NL20T05|ModelType=PCBLIB|DatafileCount=1|ModelDatafileEntity0=CAPC1608X87X45NL20T05|ModelDatafileKind0=PCBLib|DatalinksLocked=T|DatabaseDatalinksLocked=T
|RECORD=46|OwnerIndex=1121
|RECORD=48|OwnerIndex=1121
|RECORD=41|OwnerIndex=1123|IndexInSheet=-1|OwnerPartId=-1|Color=8388608|FontID=1|Text=2D|Name=Available Preview Images
|RECORD=1|LibReference=CAP|ComponentDescription=C0603X104K5RACAUTO|PartCount=2|DisplayModeCount=2|IndexInSheet=47|OwnerPartId=-1|Location.X=1110|Location.Y=390|Orientation=1|CurrentPartId=1|SourceLibraryName=Altium Content Vault|TargetFileName=*|AreaColor=11599871|Color=128|PartIDLocked=F|DesignItemId=CMP-2006-00003-1|AllPinCount=2
|RECORD=2|OwnerIndex=1125|OwnerPartId=1|OwnerPartDisplayMode=1|FormalType=1|Electrical=4|PinConglomerate=35|PinLength=10|Location.X=1120|Location.Y=390|Name=1|Designator=1|PinPropagationDelay=0.000000E+000
|RECORD=2|OwnerIndex=1125|OwnerPartId=1|OwnerPartDisplayMode=1|FormalType=1|Electrical=4|PinConglomerate=33|PinLength=10|Location.X=1120|Location.Y=400|Name=2|Designator=2|PinPropagationDelay=0.000000E+000
|RECORD=13|OwnerIndex=1125|IsNotAccesible=T|IndexInSheet=2|OwnerPartId=1|OwnerPartDisplayMode=1|Location.X=1128|Location.Y=390|Corner.X=1112|Corner.Y=390|LineWidth=1|Color=16711680
|RECORD=13|OwnerIndex=1125|IsNotAccesible=T|IndexInSheet=3|OwnerPartId=1|OwnerPartDisplayMode=1|Location.X=1120|Location.Y=394|Corner.X=1120|Corner.Y=400|LineWidth=1|Color=16711680
|RECORD=12|OwnerIndex=1125|IsNotAccesible=T|IndexInSheet=4|OwnerPartId=1|OwnerPartDisplayMode=1|Location.X=1120|Location.Y=410|Radius=16|LineWidth=1|StartAngle=241.000|EndAngle=270.000|Color=16711680
|RECORD=12|OwnerIndex=1125|IsNotAccesible=T|IndexInSheet=5|OwnerPartId=1|OwnerPartDisplayMode=1|Location.X=1120|Location.Y=410|Radius=16|LineWidth=1|StartAngle=270.000|EndAngle=299.000|Color=16711680
|RECORD=2|OwnerIndex=1125|OwnerPartId=1|FormalType=1|Electrical=4|PinConglomerate=35|PinLength=10|Location.X=1120|Location.Y=390|Name=1|Designator=1|PinPropagationDelay=0.000000E+000
|RECORD=2|OwnerIndex=1125|OwnerPartId=1|FormalType=1|Electrical=4|PinConglomerate=33|PinLength=10|Location.X=1120|Location.Y=400|Name=2|Designator=2|PinPropagationDelay=0.000000E+000
|RECORD=13|OwnerIndex=1125|IsNotAccesible=T|IndexInSheet=8|OwnerPartId=1|Location.X=1112|Location.Y=397|Corner.X=1128|Corner.Y=397|LineWidth=1|Color=16711680
|RECORD=13|OwnerIndex=1125|IsNotAccesible=T|IndexInSheet=9|OwnerPartId=1|Location.X=1128|Location.Y=393|Corner.X=1112|Corner.Y=393|LineWidth=1|Color=16711680
|RECORD=6|OwnerIndex=1125|IsNotAccesible=T|IndexInSheet=10|OwnerPartId=1|LineWidth=1|Color=16711680|LocationCount=2|X1=1120|Y1=390|X2=1120|Y2=393
|RECORD=6|OwnerIndex=1125|IsNotAccesible=T|IndexInSheet=11|OwnerPartId=1|LineWidth=1|Color=16711680|LocationCount=2|X1=1120|Y1=400|X2=1120|Y2=397
|RECORD=41|OwnerIndex=1125|IndexInSheet=12|OwnerPartId=-1|Location.X=1111|Location.Y=412|Color=8388608|FontID=1|IsHidden=T|Text=Kemet|Name=Manufacturer
|RECORD=41|OwnerIndex=1125|IndexInSheet=13|OwnerPartId=-1|Location.X=1111|Location.Y=412|Color=8388608|FontID=1|IsHidden=T|Text=C0603X104K5RACAUTO|Name=Part Number
|RECORD=34|OwnerIndex=1125|IndexInSheet=-1|OwnerPartId=-1|Location.X=1129|Location.Y=391|Color=8388608|FontID=1|Text=C10|Name=Designator|ReadOnlyState=1
|RECORD=41|OwnerIndex=1125|IndexInSheet=-1|OwnerPartId=-1|Location.X=1129|Location.Y=381|Color=8388608|FontID=1|Text=0.1uF|Name=Comment
|RECORD=44|OwnerIndex=1125
|RECORD=45|OwnerIndex=1146|IndexInSheet=-1|Description=Chip Capacitor, 2-Leads, Body 1.60x0.80mm, IPC Low Density|UseComponentLibrary=T|ModelName=CAPC1608X87X45ML20T05|ModelType=PCBLIB|DatafileCount=1|ModelDatafileEntity0=CAPC1608X87X45ML20T05|ModelDatafileKind0=PCBLib|IsCurrent=T|DatalinksLocked=T|DatabaseDatalinksLocked=T
|RECORD=46|OwnerIndex=1147
|RECORD=48|OwnerIndex=1147
|RECORD=41|OwnerIndex=1149|IndexInSheet=-1|OwnerPartId=-1|Color=8388608|FontID=1|Text=2D|Name=Available Preview Images
|RECORD=45|OwnerIndex=1146|IndexInSheet=-1|Description=Chip Capacitor, 2-Leads, Body 1.60x0.80mm, IPC High Density|UseComponentLibrary=T|ModelName=CAPC1608X87X45LL20T05|ModelType=PCBLIB|DatafileCount=1|ModelDatafileEntity0=CAPC1608X87X45LL20T05|ModelDatafileKind0=PCBLib|DatalinksLocked=T|DatabaseDatalinksLocked=T
|RECORD=46|OwnerIndex=1151
|RECORD=48|OwnerIndex=1151
|RECORD=41|OwnerIndex=1153|IndexInSheet=-1|OwnerPartId=-1|Color=8388608|FontID=1|Text=2D|Name=Available Preview Images
|RECORD=45|OwnerIndex=1146|IndexInSheet=-1|Description=Chip Capacitor, 2-Leads, Body 1.60x0.80mm, IPC Medium Density|UseComponentLibrary=T|ModelName=CAPC1608X87X45NL20T05|ModelType=PCBLIB|DatafileCount=1|ModelDatafileEntity0=CAPC1608X87X45NL20T05|ModelDatafileKind0=PCBLib|DatalinksLocked=T|DatabaseDatalinksLocked=T
|RECORD=46|OwnerIndex=1155
|RECORD=48|OwnerIndex=1155
|RECORD=41|OwnerIndex=1157|IndexInSheet=-1|OwnerPartId=-1|Color=8388608|FontID=1|Text=2D|Name=Available Preview Images
|RECORD=1|LibReference=CAP|ComponentDescription=C0603X104K5RACAUTO|PartCount=2|DisplayModeCount=2|IndexInSheet=48|OwnerPartId=-1|Location.X=1160|Location.Y=390|Orientation=1|CurrentPartId=1|SourceLibraryName=Altium Content Vault|TargetFileName=*|AreaColor=11599871|Color=128|PartIDLocked=F|DesignItemId=CMP-2006-00003-1|AllPinCount=2
|RECORD=2|OwnerIndex=1159|OwnerPartId=1|OwnerPartDisplayMode=1|FormalType=1|Electrical=4|PinConglomerate=35|PinLength=10|Location.X=1170|Location.Y=390|Name=1|Designator=1|PinPropagationDelay=0.000000E+000
|RECORD=2|OwnerIndex=1159|OwnerPartId=1|OwnerPartDisplayMode=1|FormalType=1|Electrical=4|PinConglomerate=33|PinLength=10|Location.X=1170|Location.Y=400|Name=2|Designator=2|PinPropagationDelay=0.000000E+000
|RECORD=13|OwnerIndex=1159|IsNotAccesible=T|IndexInSheet=2|OwnerPartId=1|OwnerPartDisplayMode=1|Location.X=1178|Location.Y=390|Corner.X=1162|Corner.Y=390|LineWidth=1|Color=16711680
|RECORD=13|OwnerIndex=1159|IsNotAccesible=T|IndexInSheet=3|OwnerPartId=1|OwnerPartDisplayMode=1|Location.X=1170|Location.Y=394|Corner.X=1170|Corner.Y=400|LineWidth=1|Color=16711680
|RECORD=12|OwnerIndex=1159|IsNotAccesible=T|IndexInSheet=4|OwnerPartId=1|OwnerPartDisplayMode=1|Location.X=1170|Location.Y=410|Radius=16|LineWidth=1|StartAngle=241.000|EndAngle=270.000|Color=16711680
|RECORD=12|OwnerIndex=1159|IsNotAccesible=T|IndexInSheet=5|OwnerPartId=1|OwnerPartDisplayMode=1|Location.X=1170|Location.Y=410|Radius=16|LineWidth=1|StartAngle=270.000|EndAngle=299.000|Color=16711680
|RECORD=2|OwnerIndex=1159|OwnerPartId=1|FormalType=1|Electrical=4|PinConglomerate=35|PinLength=10|Location.X=1170|Location.Y=390|Name=1|Designator=1|PinPropagationDelay=0.000000E+000
|RECORD=2|OwnerIndex=1159|OwnerPartId=1|FormalType=1|Electrical=4|PinConglomerate=33|PinLength=10|Location.X=1170|Location.Y=400|Name=2|Designator=2|PinPropagationDelay=0.000000E+000
|RECORD=13|OwnerIndex=1159|IsNotAccesible=T|IndexInSheet=8|OwnerPartId=1|Location.X=1162|Location.Y=397|Corner.X=1178|Corner.Y=397|LineWidth=1|Color=16711680
|RECORD=13|OwnerIndex=1159|IsNotAccesible=T|IndexInSheet=9|OwnerPartId=1|Location.X=1178|Location.Y=393|Corner.X=1162|Corner.Y=393|LineWidth=1|Color=16711680
|RECORD=6|OwnerIndex=1159|IsNotAccesible=T|IndexInSheet=10|OwnerPartId=1|LineWidth=1|Color=16711680|LocationCount=2|X1=1170|Y1=390|X2=1170|Y2=393
|RECORD=6|OwnerIndex=1159|IsNotAccesible=T|IndexInSheet=11|OwnerPartId=1|LineWidth=1|Color=16711680|LocationCount=2|X1=1170|Y1=400|X2=1170|Y2=397
|RECORD=41|OwnerIndex=1159|IndexInSheet=12|OwnerPartId=-1|Location.X=1161|Location.Y=412|Color=8388608|FontID=1|IsHidden=T|Text=Kemet|Name=Manufacturer
|RECORD=41|OwnerIndex=1159|IndexInSheet=13|OwnerPartId=-1|Location.X=1161|Location.Y=412|Color=8388608|FontID=1|IsHidden=T|Text=C0603X104K5RACAUTO|Name=Part Number
|RECORD=34|OwnerIndex=1159|IndexInSheet=-1|OwnerPartId=-1|Location.X=1179|Location.Y=391|Color=8388608|FontID=1|Text=C11|Name=Designator|ReadOnlyState=1
|RECORD=41|OwnerIndex=1159|IndexInSheet=-1|OwnerPartId=-1|Location.X=1179|Location.Y=381|Color=8388608|FontID=1|Text=0.1uF|Name=Comment
|RECORD=44|OwnerIndex=1159
|RECORD=45|OwnerIndex=1180|IndexInSheet=-1|Description=Chip Capacitor, 2-Leads, Body 1.60x0.80mm, IPC Low Density|UseComponentLibrary=T|ModelName=CAPC1608X87X45ML20T05|ModelType=PCBLIB|DatafileCount=1|ModelDatafileEntity0=CAPC1608X87X45ML20T05|ModelDatafileKind0=PCBLib|IsCurrent=T|DatalinksLocked=T|DatabaseDatalinksLocked=T
|RECORD=46|OwnerIndex=1181
|RECORD=48|OwnerIndex=1181
|RECORD=41|OwnerIndex=1183|IndexInSheet=-1|OwnerPartId=-1|Color=8388608|FontID=1|Text=2D|Name=Available Preview Images
|RECORD=45|OwnerIndex=1180|IndexInSheet=-1|Description=Chip Capacitor, 2-Leads, Body 1.60x0.80mm, IPC High Density|UseComponentLibrary=T|ModelName=CAPC1608X87X45LL20T05|ModelType=PCBLIB|DatafileCount=1|ModelDatafileEntity0=CAPC1608X87X45LL20T05|ModelDatafileKind0=PCBLib|DatalinksLocked=T|DatabaseDatalinksLocked=T
|RECORD=46|OwnerIndex=1185
|RECORD=48|OwnerIndex=1185
|RECORD=41|OwnerIndex=1187|IndexInSheet=-1|OwnerPartId=-1|Color=8388608|FontID=1|Text=2D|Name=Available Preview Images
|RECORD=45|OwnerIndex=1180|IndexInSheet=-1|Description=Chip Capacitor, 2-Leads, Body 1.60x0.80mm, IPC Medium Density|UseComponentLibrary=T|ModelName=CAPC1608X87X45NL20T05|ModelType=PCBLIB|DatafileCount=1|ModelDatafileEntity0=CAPC1608X87X45NL20T05|ModelDatafileKind0=PCBLib|DatalinksLocked=T|DatabaseDatalinksLocked=T
|RECORD=46|OwnerIndex=1189
|RECORD=48|OwnerIndex=1189
|RECORD=41|OwnerIndex=1191|IndexInSheet=-1|OwnerPartId=-1|Color=8388608|FontID=1|Text=2D|Name=Available Preview Images
|RECORD=1|LibReference=CAP|ComponentDescription=C0603X104K5RACAUTO|PartCount=2|DisplayModeCount=2|IndexInSheet=49|OwnerPartId=-1|Location.X=1210|Location.Y=390|Orientation=1|CurrentPartId=1|SourceLibraryName=Altium Content Vault|TargetFileName=*|AreaColor=11599871|Color=128|PartIDLocked=F|DesignItemId=CMP-2006-00003-1|AllPinCount=2
|RECORD=2|OwnerIndex=1193|OwnerPartId=1|OwnerPartDisplayMode=1|FormalType=1|Electrical=4|PinConglomerate=35|PinLength=10|Location.X=1220|Location.Y=390|Name=1|Designator=1|PinPropagationDelay=0.000000E+000
|RECORD=2|OwnerIndex=1193|OwnerPartId=1|OwnerPartDisplayMode=1|FormalType=1|Electrical=4|PinConglomerate=33|PinLength=10|Location.X=1220|Location.Y=400|Name=2|Designator=2|PinPropagationDelay=0.000000E+000
|RECORD=13|OwnerIndex=1193|IsNotAccesible=T|IndexInSheet=2|OwnerPartId=1|OwnerPartDisplayMode=1|Location.X=1228|Location.Y=390|Corner.X=1212|Corner.Y=390|LineWidth=1|Color=16711680
|RECORD=13|OwnerIndex=1193|IsNotAccesible=T|IndexInSheet=3|OwnerPartId=1|OwnerPartDisplayMode=1|Location.X=1220|Location.Y=394|Corner.X=1220|Corner.Y=400|LineWidth=1|Color=16711680
|RECORD=12|OwnerIndex=1193|IsNotAccesible=T|IndexInSheet=4|OwnerPartId=1|OwnerPartDisplayMode=1|Location.X=1220|Location.Y=410|Radius=16|LineWidth=1|StartAngle=241.000|EndAngle=270.000|Color=16711680
|RECORD=12|OwnerIndex=1193|IsNotAccesible=T|IndexInSheet=5|OwnerPartId=1|OwnerPartDisplayMode=1|Location.X=1220|Location.Y=410|Radius=16|LineWidth=1|StartAngle=270.000|EndAngle=299.000|Color=16711680
|RECORD=2|OwnerIndex=1193|OwnerPartId=1|FormalType=1|Electrical=4|PinConglomerate=35|PinLength=10|Location.X=1220|Location.Y=390|Name=1|Designator=1|PinPropagationDelay=0.000000E+000
|RECORD=2|OwnerIndex=1193|OwnerPartId=1|FormalType=1|Electrical=4|PinConglomerate=33|PinLength=10|Location.X=1220|Location.Y=400|Name=2|Designator=2|PinPropagationDelay=0.000000E+000
|RECORD=13|OwnerIndex=1193|IsNotAccesible=T|IndexInSheet=8|OwnerPartId=1|Location.X=1212|Location.Y=397|Corner.X=1228|Corner.Y=397|LineWidth=1|Color=16711680
|RECORD=13|OwnerIndex=1193|IsNotAccesible=T|IndexInSheet=9|OwnerPartId=1|Location.X=1228|Location.Y=393|Corner.X=1212|Corner.Y=393|LineWidth=1|Color=16711680
|RECORD=6|OwnerIndex=1193|IsNotAccesible=T|IndexInSheet=10|OwnerPartId=1|LineWidth=1|Color=16711680|LocationCount=2|X1=1220|Y1=390|X2=1220|Y2=393
|RECORD=6|OwnerIndex=1193|IsNotAccesible=T|IndexInSheet=11|OwnerPartId=1|LineWidth=1|Color=16711680|LocationCount=2|X1=1220|Y1=400|X2=1220|Y2=397
|RECORD=41|OwnerIndex=1193|IndexInSheet=12|OwnerPartId=-1|Location.X=1211|Location.Y=412|Color=8388608|FontID=1|IsHidden=T|Text=Kemet|Name=Manufacturer
|RECORD=41|OwnerIndex=1193|IndexInSheet=13|OwnerPartId=-1|Location.X=1211|Location.Y=412|Color=8388608|FontID=1|IsHidden=T|Text=C0603X104K5RACAUTO|Name=Part Number
|RECORD=34|OwnerIndex=1193|IndexInSheet=-1|OwnerPartId=-1|Location.X=1229|Location.Y=391|Color=8388608|FontID=1|Text=C12|Name=Designator|ReadOnlyState=1
|RECORD=41|OwnerIndex=1193|IndexInSheet=-1|OwnerPartId=-1|Location.X=1229|Location.Y=381|Color=8388608|FontID=1|Text=0.1uF|Name=Comment
|RECORD=44|OwnerIndex=1193
|RECORD=45|OwnerIndex=1214|IndexInSheet=-1|Description=Chip Capacitor, 2-Leads, Body 1.60x0.80mm, IPC Low Density|UseComponentLibrary=T|ModelName=CAPC1608X87X45ML20T05|ModelType=PCBLIB|DatafileCount=1|ModelDatafileEntity0=CAPC1608X87X45ML20T05|ModelDatafileKind0=PCBLib|IsCurrent=T|DatalinksLocked=T|DatabaseDatalinksLocked=T
|RECORD=46|OwnerIndex=1215
|RECORD=48|OwnerIndex=1215
|RECORD=41|OwnerIndex=1217|IndexInSheet=-1|OwnerPartId=-1|Color=8388608|FontID=1|Text=2D|Name=Available Preview Images
|RECORD=45|OwnerIndex=1214|IndexInSheet=-1|Description=Chip Capacitor, 2-Leads, Body 1.60x0.80mm, IPC High Density|UseComponentLibrary=T|ModelName=CAPC1608X87X45LL20T05|ModelType=PCBLIB|DatafileCount=1|ModelDatafileEntity0=CAPC1608X87X45LL20T05|ModelDatafileKind0=PCBLib|DatalinksLocked=T|DatabaseDatalinksLocked=T
|RECORD=46|OwnerIndex=1219
|RECORD=48|OwnerIndex=1219
|RECORD=41|OwnerIndex=1221|IndexInSheet=-1|OwnerPartId=-1|Color=8388608|FontID=1|Text=2D|Name=Available Preview Images
|RECORD=45|OwnerIndex=1214|IndexInSheet=-1|Description=Chip Capacitor, 2-Leads, Body 1.60x0.80mm, IPC Medium Density|UseComponentLibrary=T|ModelName=CAPC1608X87X45NL20T05|ModelType=PCBLIB|DatafileCount=1|ModelDatafileEntity0=CAPC1608X87X45NL20T05|ModelDatafileKind0=PCBLib|DatalinksLocked=T|DatabaseDatalinksLocked=T
|RECORD=46|OwnerIndex=1223
|RECORD=48|OwnerIndex=1223
|RECORD=41|OwnerIndex=1225|IndexInSheet=-1|OwnerPartId=-1|Color=8388608|FontID=1|Text=2D|Name=Available Preview Images
|RECORD=1|LibReference=CAP|ComponentDescription=GCM188R71H333KA55D|PartCount=2|DisplayModeCount=2|IndexInSheet=50|OwnerPartId=-1|Location.X=710|Location.Y=310|Orientation=1|CurrentPartId=1|SourceLibraryName=Altium Content Vault|TargetFileName=*|AreaColor=11599871|Color=128|PartIDLocked=F|DesignItemId=CMP-2006-02385-1|AllPinCount=2
|RECORD=2|OwnerIndex=1227|OwnerPartId=1|OwnerPartDisplayMode=1|FormalType=1|Electrical=4|PinConglomerate=35|PinLength=10|Location.X=720|Location.Y=310|Name=1|Designator=1|PinPropagationDelay=0.000000E+000
|RECORD=2|OwnerIndex=1227|OwnerPartId=1|OwnerPartDisplayMode=1|FormalType=1|Electrical=4|PinConglomerate=33|PinLength=10|Location.X=720|Location.Y=320|Name=2|Designator=2|PinPropagationDelay=0.000000E+000
|RECORD=13|OwnerIndex=1227|IsNotAccesible=T|IndexInSheet=2|OwnerPartId=1|OwnerPartDisplayMode=1|Location.X=728|Location.Y=310|Corner.X=712|Corner.Y=310|LineWidth=1|Color=16711680
|RECORD=13|OwnerIndex=1227|IsNotAccesible=T|IndexInSheet=3|OwnerPartId=1|OwnerPartDisplayMode=1|Location.X=720|Location.Y=314|Corner.X=720|Corner.Y=320|LineWidth=1|Color=16711680
|RECORD=12|OwnerIndex=1227|IsNotAccesible=T|IndexInSheet=4|OwnerPartId=1|OwnerPartDisplayMode=1|Location.X=720|Location.Y=330|Radius=16|LineWidth=1|StartAngle=241.000|EndAngle=270.000|Color=16711680
|RECORD=12|OwnerIndex=1227|IsNotAccesible=T|IndexInSheet=5|OwnerPartId=1|OwnerPartDisplayMode=1|Location.X=720|Location.Y=330|Radius=16|LineWidth=1|StartAngle=270.000|EndAngle=299.000|Color=16711680
|RECORD=2|OwnerIndex=1227|OwnerPartId=1|FormalType=1|Electrical=4|PinConglomerate=35|PinLength=10|Location.X=720|Location.Y=310|Name=1|Designator=1|PinPropagationDelay=0.000000E+000
|RECORD=2|OwnerIndex=1227|OwnerPartId=1|FormalType=1|Electrical=4|PinConglomerate=33|PinLength=10|Location.X=720|Location.Y=320|Name=2|Designator=2|PinPropagationDelay=0.000000E+000
|RECORD=13|OwnerIndex=1227|IsNotAccesible=T|IndexInSheet=8|OwnerPartId=1|Location.X=712|Location.Y=317|Corner.X=728|Corner.Y=317|LineWidth=1|Color=16711680
|RECORD=13|OwnerIndex=1227|IsNotAccesible=T|IndexInSheet=9|OwnerPartId=1|Location.X=728|Location.Y=313|Corner.X=712|Corner.Y=313|LineWidth=1|Color=16711680
|RECORD=6|OwnerIndex=1227|IsNotAccesible=T|IndexInSheet=10|OwnerPartId=1|LineWidth=1|Color=16711680|LocationCount=2|X1=720|Y1=310|X2=720|Y2=313
|RECORD=6|OwnerIndex=1227|IsNotAccesible=T|IndexInSheet=11|OwnerPartId=1|LineWidth=1|Color=16711680|LocationCount=2|X1=720|Y1=320|X2=720|Y2=317
|RECORD=41|OwnerIndex=1227|IndexInSheet=12|OwnerPartId=-1|Location.X=711|Location.Y=332|Color=8388608|FontID=1|IsHidden=T|Text=Murata|Name=Manufacturer
|RECORD=41|OwnerIndex=1227|IndexInSheet=13|OwnerPartId=-1|Location.X=711|Location.Y=332|Color=8388608|FontID=1|IsHidden=T|Text=GCM188R71H333KA55D|Name=Part Number
|RECORD=34|OwnerIndex=1227|IndexInSheet=-1|OwnerPartId=-1|Location.X=729|Location.Y=311|Color=8388608|FontID=1|Text=C22|Name=Designator|ReadOnlyState=1
|RECORD=41|OwnerIndex=1227|IndexInSheet=-1|OwnerPartId=-1|Location.X=729|Location.Y=301|Color=8388608|FontID=1|Text=0.033uF|Name=Comment
|RECORD=44|OwnerIndex=1227
|RECORD=45|OwnerIndex=1248|IndexInSheet=-1|Description=Chip Capacitor, 2-Leads, Body 1.60x0.80mm, IPC Medium Density|UseComponentLibrary=T|ModelName=CAPC1608X90X35NL10T15|ModelType=PCBLIB|DatafileCount=1|ModelDatafileEntity0=CAPC1608X90X35NL10T15|ModelDatafileKind0=PCBLib|IsCurrent=T|DatalinksLocked=T|DatabaseDatalinksLocked=T
|RECORD=46|OwnerIndex=1249
|RECORD=48|OwnerIndex=1249
|RECORD=41|OwnerIndex=1251|IndexInSheet=-1|OwnerPartId=-1|Color=8388608|FontID=1|Text=2D|Name=Available Preview Images
|RECORD=45|OwnerIndex=1248|IndexInSheet=-1|Description=Chip Capacitor, 2-Leads, Body 1.60x0.80mm, IPC Low Density|UseComponentLibrary=T|ModelName=CAPC1608X90X35ML10T15|ModelType=PCBLIB|DatafileCount=1|ModelDatafileEntity0=CAPC1608X90X35ML10T15|ModelDatafileKind0=PCBLib|DatalinksLocked=T|DatabaseDatalinksLocked=T
|RECORD=46|OwnerIndex=1253
|RECORD=48|OwnerIndex=1253
|RECORD=41|OwnerIndex=1255|IndexInSheet=-1|OwnerPartId=-1|Color=8388608|FontID=1|Text=2D|Name=Available Preview Images
|RECORD=45|OwnerIndex=1248|IndexInSheet=-1|Description=Chip Capacitor, 2-Leads, Body 1.60x0.80mm, IPC High Density|UseComponentLibrary=T|ModelName=CAPC1608X90X35LL10T15|ModelType=PCBLIB|DatafileCount=1|ModelDatafileEntity0=CAPC1608X90X35LL10T15|ModelDatafileKind0=PCBLib|DatalinksLocked=T|DatabaseDatalinksLocked=T
|RECORD=46|OwnerIndex=1257
|RECORD=48|OwnerIndex=1257
|RECORD=41|OwnerIndex=1259|IndexInSheet=-1|OwnerPartId=-1|Color=8388608|FontID=1|Text=2D|Name=Available Preview Images
|RECORD=1|LibReference=CAP|ComponentDescription=GCM188R71H333KA55D|PartCount=2|DisplayModeCount=2|IndexInSheet=51|OwnerPartId=-1|Location.X=730|Location.Y=750|Orientation=1|CurrentPartId=1|SourceLibraryName=Altium Content Vault|TargetFileName=*|AreaColor=11599871|Color=128|PartIDLocked=F|DesignItemId=CMP-2006-02385-1|AllPinCount=2
|RECORD=2|OwnerIndex=1261|OwnerPartId=1|OwnerPartDisplayMode=1|FormalType=1|Electrical=4|PinConglomerate=35|PinLength=10|Location.X=740|Location.Y=750|Name=1|Designator=1|PinPropagationDelay=0.000000E+000
|RECORD=2|OwnerIndex=1261|OwnerPartId=1|OwnerPartDisplayMode=1|FormalType=1|Electrical=4|PinConglomerate=33|PinLength=10|Location.X=740|Location.Y=760|Name=2|Designator=2|PinPropagationDelay=0.000000E+000
|RECORD=13|OwnerIndex=1261|IsNotAccesible=T|IndexInSheet=2|OwnerPartId=1|OwnerPartDisplayMode=1|Location.X=748|Location.Y=750|Corner.X=732|Corner.Y=750|LineWidth=1|Color=16711680
|RECORD=13|OwnerIndex=1261|IsNotAccesible=T|IndexInSheet=3|OwnerPartId=1|OwnerPartDisplayMode=1|Location.X=740|Location.Y=754|Corner.X=740|Corner.Y=760|LineWidth=1|Color=16711680
|RECORD=12|OwnerIndex=1261|IsNotAccesible=T|IndexInSheet=4|OwnerPartId=1|OwnerPartDisplayMode=1|Location.X=740|Location.Y=770|Radius=16|LineWidth=1|StartAngle=241.000|EndAngle=270.000|Color=16711680
|RECORD=12|OwnerIndex=1261|IsNotAccesible=T|IndexInSheet=5|OwnerPartId=1|OwnerPartDisplayMode=1|Location.X=740|Location.Y=770|Radius=16|LineWidth=1|StartAngle=270.000|EndAngle=299.000|Color=16711680
|RECORD=2|OwnerIndex=1261|OwnerPartId=1|FormalType=1|Electrical=4|PinConglomerate=35|PinLength=10|Location.X=740|Location.Y=750|Name=1|Designator=1|PinPropagationDelay=0.000000E+000
|RECORD=2|OwnerIndex=1261|OwnerPartId=1|FormalType=1|Electrical=4|PinConglomerate=33|PinLength=10|Location.X=740|Location.Y=760|Name=2|Designator=2|PinPropagationDelay=0.000000E+000
|RECORD=13|OwnerIndex=1261|IsNotAccesible=T|IndexInSheet=8|OwnerPartId=1|Location.X=732|Location.Y=757|Corner.X=748|Corner.Y=757|LineWidth=1|Color=16711680
|RECORD=13|OwnerIndex=1261|IsNotAccesible=T|IndexInSheet=9|OwnerPartId=1|Location.X=748|Location.Y=753|Corner.X=732|Corner.Y=753|LineWidth=1|Color=16711680
|RECORD=6|OwnerIndex=1261|IsNotAccesible=T|IndexInSheet=10|OwnerPartId=1|LineWidth=1|Color=16711680|LocationCount=2|X1=740|Y1=750|X2=740|Y2=753
|RECORD=6|OwnerIndex=1261|IsNotAccesible=T|IndexInSheet=11|OwnerPartId=1|LineWidth=1|Color=16711680|LocationCount=2|X1=740|Y1=760|X2=740|Y2=757
|RECORD=41|OwnerIndex=1261|IndexInSheet=12|OwnerPartId=-1|Location.X=731|Location.Y=772|Color=8388608|FontID=1|IsHidden=T|Text=Murata|Name=Manufacturer
|RECORD=41|OwnerIndex=1261|IndexInSheet=13|OwnerPartId=-1|Location.X=731|Location.Y=772|Color=8388608|FontID=1|IsHidden=T|Text=GCM188R71H333KA55D|Name=Part Number
|RECORD=34|OwnerIndex=1261|IndexInSheet=-1|OwnerPartId=-1|Location.X=749|Location.Y=751|Color=8388608|FontID=1|Text=C20|Name=Designator|ReadOnlyState=1
|RECORD=41|OwnerIndex=1261|IndexInSheet=-1|OwnerPartId=-1|Location.X=749|Location.Y=741|Color=8388608|FontID=1|Text=0.033uF|Name=Comment
|RECORD=44|OwnerIndex=1261
|RECORD=45|OwnerIndex=1282|IndexInSheet=-1|Description=Chip Capacitor, 2-Leads, Body 1.60x0.80mm, IPC Medium Density|UseComponentLibrary=T|ModelName=CAPC1608X90X35NL10T15|ModelType=PCBLIB|DatafileCount=1|ModelDatafileEntity0=CAPC1608X90X35NL10T15|ModelDatafileKind0=PCBLib|IsCurrent=T|DatalinksLocked=T|DatabaseDatalinksLocked=T
|RECORD=46|OwnerIndex=1283
|RECORD=48|OwnerIndex=1283
|RECORD=41|OwnerIndex=1285|IndexInSheet=-1|OwnerPartId=-1|Color=8388608|FontID=1|Text=2D|Name=Available Preview Images
|RECORD=45|OwnerIndex=1282|IndexInSheet=-1|Description=Chip Capacitor, 2-Leads, Body 1.60x0.80mm, IPC Low Density|UseComponentLibrary=T|ModelName=CAPC1608X90X35ML10T15|ModelType=PCBLIB|DatafileCount=1|ModelDatafileEntity0=CAPC1608X90X35ML10T15|ModelDatafileKind0=PCBLib|DatalinksLocked=T|DatabaseDatalinksLocked=T
|RECORD=46|OwnerIndex=1287
|RECORD=48|OwnerIndex=1287
|RECORD=41|OwnerIndex=1289|IndexInSheet=-1|OwnerPartId=-1|Color=8388608|FontID=1|Text=2D|Name=Available Preview Images
|RECORD=45|OwnerIndex=1282|IndexInSheet=-1|Description=Chip Capacitor, 2-Leads, Body 1.60x0.80mm, IPC High Density|UseComponentLibrary=T|ModelName=CAPC1608X90X35LL10T15|ModelType=PCBLIB|DatafileCount=1|ModelDatafileEntity0=CAPC1608X90X35LL10T15|ModelDatafileKind0=PCBLib|DatalinksLocked=T|DatabaseDatalinksLocked=T
|RECORD=46|OwnerIndex=1291
|RECORD=48|OwnerIndex=1291
|RECORD=41|OwnerIndex=1293|IndexInSheet=-1|OwnerPartId=-1|Color=8388608|FontID=1|Text=2D|Name=Available Preview Images
|RECORD=41|IndexInSheet=52|OwnerPartId=-1|Color=8388608|FontID=1|IsHidden=T|Name=ConfigurationParameters|ReadOnlyState=1
|RECORD=41|IndexInSheet=53|OwnerPartId=-1|Color=8388608|FontID=1|IsHidden=T|Name=ConfiguratorName|ReadOnlyState=1
|RECORD=41|IndexInSheet=54|OwnerPartId=-1|Color=8388608|FontID=1|IsHidden=T|Name=VersionControl_RevNumber|ReadOnlyState=1
|RECORD=41|IndexInSheet=55|OwnerPartId=-1|Color=8388608|FontID=1|IsHidden=T|Name=IsUserConfigurable|ReadOnlyState=1
|RECORD=41|IndexInSheet=56|OwnerPartId=-1|Color=8388608|FontID=1|IsHidden=T|Name=VersionControl_ProjFolderRevNumber|ReadOnlyState=1
|RECORD=41|IndexInSheet=57|OwnerPartId=-1|Color=8388608|FontID=1|IsHidden=T|Name=SPICEModelCache|ReadOnlyState=1
|RECORD=41|IndexInSheet=58|OwnerPartId=-1|Color=8388608|FontID=1|IsHidden=T|Text=*|Name=CurrentTime|ReadOnlyState=1
|RECORD=41|IndexInSheet=59|OwnerPartId=-1|Color=8388608|FontID=1|IsHidden=T|Text=*|Name=CurrentDate|ReadOnlyState=1
|RECORD=41|IndexInSheet=60|OwnerPartId=-1|Color=8388608|FontID=1|IsHidden=T|Text=*|Name=Time|ReadOnlyState=1
|RECORD=41|IndexInSheet=61|OwnerPartId=-1|Color=8388608|FontID=1|IsHidden=T|Text=*|Name=Date|ReadOnlyState=1
|RECORD=41|IndexInSheet=62|OwnerPartId=-1|Color=8388608|FontID=1|IsHidden=T|Text=*|Name=DocumentFullPathAndName|ReadOnlyState=1
|RECORD=41|IndexInSheet=63|OwnerPartId=-1|Color=8388608|FontID=1|IsHidden=T|Text=*|Name=DocumentName|ReadOnlyState=1
|RECORD=41|IndexInSheet=64|OwnerPartId=-1|Color=8388608|FontID=1|IsHidden=T|Text=*|Name=ModifiedDate|ReadOnlyState=1
|RECORD=41|IndexInSheet=65|OwnerPartId=-1|Color=8388608|FontID=1|IsHidden=T|Text=*|Name=ApprovedBy|ReadOnlyState=1
|RECORD=41|IndexInSheet=66|OwnerPartId=-1|Color=8388608|FontID=1|IsHidden=T|Text=*|Name=CheckedBy|ReadOnlyState=1
|RECORD=41|IndexInSheet=67|OwnerPartId=-1|Color=8388608|FontID=1|IsHidden=T|Text=*|Name=Author|ReadOnlyState=1
|RECORD=41|IndexInSheet=68|OwnerPartId=-1|Color=8388608|FontID=1|IsHidden=T|Text=*|Name=CompanyName|ReadOnlyState=1
|RECORD=41|IndexInSheet=69|OwnerPartId=-1|Color=8388608|FontID=1|IsHidden=T|Text=*|Name=DrawnBy|ReadOnlyState=1
|RECORD=41|IndexInSheet=70|OwnerPartId=-1|Color=8388608|FontID=1|IsHidden=T|Text=*|Name=Engineer|ReadOnlyState=1
|RECORD=41|IndexInSheet=71|OwnerPartId=-1|Color=8388608|FontID=1|IsHidden=T|Text=*|Name=Organization|ReadOnlyState=1
|RECORD=41|IndexInSheet=72|OwnerPartId=-1|Color=8388608|FontID=1|IsHidden=T|Text=*|Name=Address1|ReadOnlyState=1
|RECORD=41|IndexInSheet=73|OwnerPartId=-1|Color=8388608|FontID=1|IsHidden=T|Text=*|Name=Address2|ReadOnlyState=1
|RECORD=41|IndexInSheet=74|OwnerPartId=-1|Color=8388608|FontID=1|IsHidden=T|Text=*|Name=Address3|ReadOnlyState=1
|RECORD=41|IndexInSheet=75|OwnerPartId=-1|Color=8388608|FontID=1|IsHidden=T|Text=*|Name=Address4|ReadOnlyState=1
|RECORD=41|IndexInSheet=76|OwnerPartId=-1|Color=8388608|FontID=1|IsHidden=T|Text=*|Name=Title|ReadOnlyState=1
|RECORD=41|IndexInSheet=77|OwnerPartId=-1|Color=8388608|FontID=1|IsHidden=T|Text=*|Name=DocumentNumber|ReadOnlyState=1
|RECORD=41|IndexInSheet=78|OwnerPartId=-1|Color=8388608|FontID=1|IsHidden=T|Text=*|Name=Revision|ReadOnlyState=1
|RECORD=41|IndexInSheet=79|OwnerPartId=-1|Color=8388608|FontID=1|IsHidden=T|Text=*|Name=SheetNumber|ReadOnlyState=1
|RECORD=41|IndexInSheet=80|OwnerPartId=-1|Color=8388608|FontID=1|IsHidden=T|Text=*|Name=SheetTotal|ReadOnlyState=1
|RECORD=41|IndexInSheet=81|OwnerPartId=-1|Color=8388608|FontID=1|IsHidden=T|Text=*|Name=Rule|ReadOnlyState=1
|RECORD=41|IndexInSheet=82|OwnerPartId=-1|Color=8388608|FontID=1|IsHidden=T|Text=*|Name=ImagePath|ReadOnlyState=1
|RECORD=41|IndexInSheet=83|OwnerPartId=-1|Color=8388608|FontID=1|IsHidden=T|Text=*|Name=ProjectName|ReadOnlyState=1
|RECORD=41|IndexInSheet=84|OwnerPartId=-1|Color=8388608|FontID=1|IsHidden=T|Text=*|Name=Application_BuildNumber|ReadOnlyState=1
|RECORD=17|IndexInSheet=85|OwnerPartId=-1|Style=4|ShowNetName=T|Location.X=175|Location.Y=783|Orientation=3|Color=128|FontID=1|Text=GND
|RECORD=1|LibReference=39-30-1060|ComponentDescription=CONN, HDR, 2X3, R/A, 4.2MM, TH, MINI-FIT JR|PartCount=2|DisplayModeCount=1|IndexInSheet=86|OwnerPartId=-1|Location.X=125|Location.Y=863|IsMirrored=T|CurrentPartId=1|LibraryPath=*|SourceLibraryName=Connectors.IntLib|TargetFileName=*|AreaColor=11599871|Color=128|PartIDLocked=F|DesignItemId=39-30-1060|AllPinCount=6
|RECORD=41|OwnerIndex=1329|OwnerPartId=-1|Location.X=64|Location.Y=869|Color=8388608|FontID=6|IsHidden=T|Text=10/10/2013|Name=MODIFY DATE|IsMirrored=T
|RECORD=41|OwnerIndex=1329|IndexInSheet=1|OwnerPartId=-1|Location.X=64|Location.Y=869|Color=8388608|FontID=6|IsHidden=T|Text=105314-1206|Name=MFG PART NUM|IsMirrored=T
|RECORD=41|OwnerIndex=1329|IndexInSheet=2|OwnerPartId=-1|Location.X=64|Location.Y=869|Color=8388608|FontID=6|IsHidden=T|Text=MOLEX|Name=MFG NAME|IsMirrored=T
|RECORD=41|OwnerIndex=1329|IndexInSheet=3|OwnerPartId=-1|Location.X=64|Location.Y=869|Color=8388608|FontID=6|IsHidden=T|Text=CONN, HDR|Name=CATEGORY|IsMirrored=T
|RECORD=41|OwnerIndex=1329|IndexInSheet=4|OwnerPartId=-1|Location.X=64|Location.Y=869|Color=8388608|FontID=6|IsHidden=T|Text=105C|Name=MAXTEMP|IsMirrored=T
|RECORD=41|OwnerIndex=1329|IndexInSheet=5|OwnerPartId=-1|Location.X=64|Location.Y=869|Color=8388608|FontID=6|IsHidden=T|Text=-40C|Name=MINTEMP|IsMirrored=T
|RECORD=41|OwnerIndex=1329|IndexInSheet=6|OwnerPartId=-1|Location.X=64|Location.Y=869|Color=8388608|FontID=6|IsHidden=T|Text=NANO-FIT|Name=OTHER|IsMirrored=T
|RECORD=41|OwnerIndex=1329|IndexInSheet=7|OwnerPartId=-1|Location.X=64|Location.Y=869|Color=8388608|FontID=6|IsHidden=T|Text=R/A|Name=P1|IsMirrored=T
|RECORD=41|OwnerIndex=1329|IndexInSheet=8|OwnerPartId=-1|Location.X=64|Location.Y=869|Color=8388608|FontID=6|IsHidden=T|Text=2.5MM|Name=P2|IsMirrored=T
|RECORD=41|OwnerIndex=1329|IndexInSheet=9|OwnerPartId=-1|Location.X=64|Location.Y=869|Color=8388608|FontID=6|IsHidden=T|Name=P3|IsMirrored=T
|RECORD=41|OwnerIndex=1329|IndexInSheet=10|OwnerPartId=-1|Location.X=64|Location.Y=869|Color=8388608|FontID=6|IsHidden=T|Text=TH|Name=SIZE|IsMirrored=T
|RECORD=41|OwnerIndex=1329|IndexInSheet=11|OwnerPartId=-1|Location.X=64|Location.Y=869|Color=8388608|FontID=6|IsHidden=T|Name=SUB|IsMirrored=T
|RECORD=41|OwnerIndex=1329|IndexInSheet=12|OwnerPartId=-1|Location.X=64|Location.Y=869|Color=8388608|FontID=6|IsHidden=T|Name=SHEETPART|IsMirrored=T
|RECORD=41|OwnerIndex=1329|IndexInSheet=13|OwnerPartId=-1|Location.X=64|Location.Y=869|Color=8388608|FontID=6|IsHidden=T|Name=DATE|IsMirrored=T
|RECORD=41|OwnerIndex=1329|IndexInSheet=14|OwnerPartId=-1|Location.X=64|Location.Y=869|Color=8388608|FontID=1|IsHidden=T|Text=CONN, HDR, 2X3, R/A, 2.5MM, TH, NANO-FIT|Name=DESC|IsMirrored=T
|RECORD=41|OwnerIndex=1329|IndexInSheet=15|OwnerPartId=-1|Location.X=64|Location.Y=869|Color=8388608|FontID=1|IsHidden=T|Text=Digi-Key|Name=Supplier 1|ReadOnlyState=3|IsMirrored=T
|RECORD=41|OwnerIndex=1329|IndexInSheet=16|OwnerPartId=-1|Location.X=64|Location.Y=869|Color=8388608|FontID=1|IsHidden=T|Text=WM14977-ND|Name=Supplier Part Number 1|ReadOnlyState=3|IsMirrored=T
|RECORD=41|OwnerIndex=1329|IndexInSheet=17|OwnerPartId=-1|Location.X=64|Location.Y=869|Color=8388608|FontID=1|IsHidden=T|Text=<VALENTIUM>|Name=VALENTIUM PART NUM|IsMirrored=T
|RECORD=41|OwnerIndex=1329|IndexInSheet=18|OwnerPartId=-1|Location.X=64|Location.Y=795|Color=8388608|FontID=6|Text=2X3|Name=VALUE|IsMirrored=T
|RECORD=2|OwnerIndex=1329|OwnerPartId=1|FormalType=1|Electrical=4|PinConglomerate=56|PinLength=30|Location.X=95|Location.Y=813|Designator=6|SwapIdPin=6|SwapIDPart=1|PinPropagationDelay=0.000000E+000
|RECORD=2|OwnerIndex=1329|OwnerPartId=1|FormalType=1|Electrical=4|PinConglomerate=56|PinLength=30|Location.X=95|Location.Y=823|Designator=5|SwapIdPin=5|SwapIDPart=1|PinPropagationDelay=0.000000E+000
|RECORD=2|OwnerIndex=1329|OwnerPartId=1|FormalType=1|Electrical=4|PinConglomerate=56|PinLength=30|Location.X=95|Location.Y=833|Designator=4|SwapIdPin=4|SwapIDPart=1|PinPropagationDelay=0.000000E+000
|RECORD=2|OwnerIndex=1329|OwnerPartId=1|FormalType=1|Electrical=4|PinConglomerate=56|PinLength=30|Location.X=95|Location.Y=843|Designator=3|SwapIdPin=3|SwapIDPart=1|PinPropagationDelay=0.000000E+000
|RECORD=2|OwnerIndex=1329|OwnerPartId=1|FormalType=1|Electrical=4|PinConglomerate=56|PinLength=30|Location.X=95|Location.Y=853|Designator=2|SwapIdPin=2|SwapIDPart=1|PinPropagationDelay=0.000000E+000
|RECORD=2|OwnerIndex=1329|OwnerPartId=1|FormalType=1|Electrical=4|PinConglomerate=56|PinLength=30|Location.X=95|Location.Y=863|Designator=1|SwapIdPin=1|SwapIDPart=1|PinPropagationDelay=0.000000E+000
|RECORD=13|OwnerIndex=1329|IsNotAccesible=T|IndexInSheet=25|OwnerPartId=1|Location.X=88|Location.Y=863|Corner.X=95|Corner.Y=863|LineWidth=1|Color=16711680
|RECORD=13|OwnerIndex=1329|IsNotAccesible=T|IndexInSheet=26|OwnerPartId=1|Location.X=82|Location.Y=863|Corner.X=88|Corner.Y=863|LineWidth=1|Color=16711680
|RECORD=13|OwnerIndex=1329|IsNotAccesible=T|IndexInSheet=27|OwnerPartId=1|Location.X=88|Location.Y=853|Corner.X=95|Corner.Y=853|LineWidth=1|Color=16711680
|RECORD=13|OwnerIndex=1329|IsNotAccesible=T|IndexInSheet=28|OwnerPartId=1|Location.X=82|Location.Y=853|Corner.X=88|Corner.Y=853|LineWidth=1|Color=16711680
|RECORD=13|OwnerIndex=1329|IsNotAccesible=T|IndexInSheet=29|OwnerPartId=1|Location.X=87|Location.Y=858|Corner.X=82|Corner.Y=853|LineWidth=1|Color=16711680
|RECORD=13|OwnerIndex=1329|IsNotAccesible=T|IndexInSheet=30|OwnerPartId=1|Location.X=87|Location.Y=858|Corner.X=82|Corner.Y=863|LineWidth=1|Color=16711680
|RECORD=13|OwnerIndex=1329|IsNotAccesible=T|IndexInSheet=31|OwnerPartId=1|Location.X=87|Location.Y=868|Corner.X=82|Corner.Y=863|LineWidth=1|Color=16711680
|RECORD=13|OwnerIndex=1329|IsNotAccesible=T|IndexInSheet=32|OwnerPartId=1|Location.X=87|Location.Y=848|Corner.X=82|Corner.Y=853|LineWidth=1|Color=16711680
|RECORD=13|OwnerIndex=1329|IsNotAccesible=T|IndexInSheet=33|OwnerPartId=1|Location.X=88|Location.Y=843|Corner.X=95|Corner.Y=843|LineWidth=1|Color=16711680
|RECORD=13|OwnerIndex=1329|IsNotAccesible=T|IndexInSheet=34|OwnerPartId=1|Location.X=82|Location.Y=843|Corner.X=88|Corner.Y=843|LineWidth=1|Color=16711680
|RECORD=13|OwnerIndex=1329|IsNotAccesible=T|IndexInSheet=35|OwnerPartId=1|Location.X=88|Location.Y=833|Corner.X=95|Corner.Y=833|LineWidth=1|Color=16711680
|RECORD=13|OwnerIndex=1329|IsNotAccesible=T|IndexInSheet=36|OwnerPartId=1|Location.X=82|Location.Y=833|Corner.X=88|Corner.Y=833|LineWidth=1|Color=16711680
|RECORD=13|OwnerIndex=1329|IsNotAccesible=T|IndexInSheet=37|OwnerPartId=1|Location.X=87|Location.Y=838|Corner.X=82|Corner.Y=833|LineWidth=1|Color=16711680
|RECORD=13|OwnerIndex=1329|IsNotAccesible=T|IndexInSheet=38|OwnerPartId=1|Location.X=87|Location.Y=838|Corner.X=82|Corner.Y=843|LineWidth=1|Color=16711680
|RECORD=13|OwnerIndex=1329|IsNotAccesible=T|IndexInSheet=39|OwnerPartId=1|Location.X=87|Location.Y=848|Corner.X=82|Corner.Y=843|LineWidth=1|Color=16711680
|RECORD=13|OwnerIndex=1329|IsNotAccesible=T|IndexInSheet=40|OwnerPartId=1|Location.X=87|Location.Y=828|Corner.X=82|Corner.Y=833|LineWidth=1|Color=16711680
|RECORD=13|OwnerIndex=1329|IsNotAccesible=T|IndexInSheet=41|OwnerPartId=1|Location.X=88|Location.Y=823|Corner.X=95|Corner.Y=823|LineWidth=1|Color=16711680
|RECORD=13|OwnerIndex=1329|IsNotAccesible=T|IndexInSheet=42|OwnerPartId=1|Location.X=82|Location.Y=823|Corner.X=88|Corner.Y=823|LineWidth=1|Color=16711680
|RECORD=13|OwnerIndex=1329|IsNotAccesible=T|IndexInSheet=43|OwnerPartId=1|Location.X=88|Location.Y=813|Corner.X=95|Corner.Y=813|LineWidth=1|Color=16711680
|RECORD=13|OwnerIndex=1329|IsNotAccesible=T|IndexInSheet=44|OwnerPartId=1|Location.X=82|Location.Y=813|Corner.X=88|Corner.Y=813|LineWidth=1|Color=16711680
|RECORD=13|OwnerIndex=1329|IsNotAccesible=T|IndexInSheet=45|OwnerPartId=1|Location.X=87|Location.Y=818|Corner.X=82|Corner.Y=813|LineWidth=1|Color=16711680
|RECORD=13|OwnerIndex=1329|IsNotAccesible=T|IndexInSheet=46|OwnerPartId=1|Location.X=87|Location.Y=818|Corner.X=82|Corner.Y=823|LineWidth=1|Color=16711680
|RECORD=13|OwnerIndex=1329|IsNotAccesible=T|IndexInSheet=47|OwnerPartId=1|Location.X=87|Location.Y=828|Corner.X=82|Corner.Y=823|LineWidth=1|Color=16711680
|RECORD=13|OwnerIndex=1329|IsNotAccesible=T|IndexInSheet=48|OwnerPartId=1|Location.X=87|Location.Y=808|Corner.X=82|Corner.Y=813|LineWidth=1|Color=16711680
|RECORD=13|OwnerIndex=1329|IsNotAccesible=T|IndexInSheet=49|OwnerPartId=1|Location.X=95|Location.Y=808|Corner.X=65|Corner.Y=808|LineWidth=1|Color=16711680
|RECORD=13|OwnerIndex=1329|IsNotAccesible=T|IndexInSheet=50|OwnerPartId=1|Location.X=65|Location.Y=868|Corner.X=95|Corner.Y=868|LineWidth=1|Color=16711680
|RECORD=13|OwnerIndex=1329|IsNotAccesible=T|IndexInSheet=51|OwnerPartId=1|Location.X=65|Location.Y=808|Corner.X=65|Corner.Y=868|LineWidth=1|Color=16711680
|RECORD=13|OwnerIndex=1329|IsNotAccesible=T|IndexInSheet=52|OwnerPartId=1|Location.X=95|Location.Y=868|Corner.X=95|Corner.Y=808|LineWidth=1|Color=16711680
|RECORD=34|OwnerIndex=1329|IndexInSheet=-1|OwnerPartId=-1|Location.X=64|Location.Y=869|Color=8388608|FontID=7|Text=J38|Name=Designator|ReadOnlyState=1|IsMirrored=T
|RECORD=41|OwnerIndex=1329|IndexInSheet=-1|OwnerPartId=-1|Location.X=64|Location.Y=869|Color=8388608|FontID=6|IsHidden=T|Text=39-30-1060|Name=Comment|ReadOnlyState=1|IsMirrored=T
|RECORD=44|OwnerIndex=1329
|RECORD=45|OwnerIndex=1391|IndexInSheet=-1|Description=HDR 2X3 MINI-FIT JR R/A 4.2MM|UseComponentLibrary=T|ModelName=39-30-1060|ModelType=PCBLIB|DatafileCount=1|ModelDatafileEntity0=39-30-1060|ModelDatafileKind0=PCBLib|IsCurrent=T|DatalinksLocked=T|DatabaseDatalinksLocked=T|IntegratedModel=T|DatabaseModel=T
|RECORD=46|OwnerIndex=1392
|RECORD=48|OwnerIndex=1392
|RECORD=17|IndexInSheet=87|OwnerPartId=-1|ShowNetName=T|Location.X=87|Location.Y=709|Orientation=1|Color=128|FontID=1|Text=+12V_PCIE
|RECORD=1|LibReference=1d6ec82d83fb6aee721767c19dac4b9|ComponentDescription=DIODE SCHOTTKY 60V 5A SMC|PartCount=2|DisplayModeCount=1|IndexInSheet=88|OwnerPartId=-1|Location.X=225|Location.Y=870|CurrentPartId=1|LibraryPath=*|SourceLibraryName=Altium Content Vault|TargetFileName=*|AreaColor=11599871|Color=128|PartIDLocked=T|DesignItemId=CMP-12187-000009-2|AllPinCount=2
|RECORD=2|OwnerIndex=1396|OwnerPartId=1|Electrical=4|PinConglomerate=50|PinLength=20|Location.X=245|Location.Y=870|Name=A|Designator=2|PinPropagationDelay=0.000000E+000
|RECORD=2|OwnerIndex=1396|OwnerPartId=1|Electrical=4|PinConglomerate=48|PinLength=20|Location.X=265|Location.Y=870|Name=C|Designator=1|PinPropagationDelay=0.000000E+000
|RECORD=13|OwnerIndex=1396|IsNotAccesible=T|IndexInSheet=2|OwnerPartId=1|Location.X=245|Location.Y=880|Corner.X=245|Corner.Y=860|LineWidth=1|Color=16711680
|RECORD=13|OwnerIndex=1396|IsNotAccesible=T|IndexInSheet=3|OwnerPartId=1|Location.X=265|Location.Y=880|Corner.X=265|Corner.Y=860|LineWidth=1|Color=16711680
|RECORD=13|OwnerIndex=1396|IsNotAccesible=T|IndexInSheet=4|OwnerPartId=1|Location.X=245|Location.Y=880|Corner.X=265|Corner.Y=870|LineWidth=1|Color=16711680
|RECORD=13|OwnerIndex=1396|IsNotAccesible=T|IndexInSheet=5|OwnerPartId=1|Location.X=245|Location.Y=860|Corner.X=265|Corner.Y=870|LineWidth=1|Color=16711680
|RECORD=13|OwnerIndex=1396|IsNotAccesible=T|IndexInSheet=6|OwnerPartId=1|Location.X=265|Location.Y=880|Corner.X=262|Corner.Y=880|LineWidth=1|Color=16711680
|RECORD=13|OwnerIndex=1396|IsNotAccesible=T|IndexInSheet=7|OwnerPartId=1|Location.X=268|Location.Y=860|Corner.X=268|Corner.Y=863|LineWidth=1|Color=16711680
|RECORD=13|OwnerIndex=1396|IsNotAccesible=T|IndexInSheet=8|OwnerPartId=1|Location.X=262|Location.Y=880|Corner.X=262|Corner.Y=877|LineWidth=1|Color=16711680
|RECORD=13|OwnerIndex=1396|IsNotAccesible=T|IndexInSheet=9|OwnerPartId=1|Location.X=265|Location.Y=860|Corner.X=268|Corner.Y=860|LineWidth=1|Color=16711680
|RECORD=13|OwnerIndex=1396|IsNotAccesible=T|IndexInSheet=10|OwnerPartId=1|Location.X=245|Location.Y=870|Corner.X=242|Corner.Y=870|LineWidth=1|Color=16711680
|RECORD=13|OwnerIndex=1396|IsNotAccesible=T|IndexInSheet=11|OwnerPartId=1|Location.X=265|Location.Y=870|Corner.X=268|Corner.Y=870|LineWidth=1|Color=16711680
|RECORD=41|OwnerIndex=1396|IndexInSheet=12|OwnerPartId=-1|Location.X=223|Location.Y=881|Color=8388608|FontID=1|IsHidden=T|Text=No|Name=Radiation Hardening
|RECORD=41|OwnerIndex=1396|IndexInSheet=13|OwnerPartId=-1|Location.X=223|Location.Y=881|Color=8388608|FontID=1|IsHidden=T|Text=150A|Name=Max Forward Surge Current (Ifsm)
|RECORD=41|OwnerIndex=1396|IndexInSheet=14|OwnerPartId=-1|Location.X=223|Location.Y=881|Color=8388608|FontID=1|IsHidden=T|Text=2500|Name=Package Quantity
|RECORD=41|OwnerIndex=1396|IndexInSheet=15|OwnerPartId=-1|Location.X=223|Location.Y=881|Color=8388608|FontID=1|IsHidden=T|Text=No SVHC|Name=REACH SVHC
|RECORD=41|OwnerIndex=1396|IndexInSheet=16|OwnerPartId=-1|Location.X=223|Location.Y=881|Color=8388608|FontID=1|IsHidden=T|Text=60V|Name=Max Reverse Voltage (DC)
|RECORD=41|OwnerIndex=1396|IndexInSheet=17|OwnerPartId=-1|Location.X=223|Location.Y=881|Color=8388608|FontID=1|IsHidden=T|Text=2|Name=Number of Pins
|RECORD=41|OwnerIndex=1396|IndexInSheet=18|OwnerPartId=-1|Location.X=223|Location.Y=881|Color=8388608|FontID=1|IsHidden=T|Text=Surface Mount|Name=Mount
|RECORD=41|OwnerIndex=1396|IndexInSheet=19|OwnerPartId=-1|Location.X=223|Location.Y=881|Color=8388608|FontID=1|IsHidden=T|Text=2.45mm|Name=Height
|RECORD=41|OwnerIndex=1396|IndexInSheet=20|OwnerPartId=-1|Location.X=223|Location.Y=881|Color=8388608|FontID=1|IsHidden=T|Text=5A|Name=Forward Current
|RECORD=41|OwnerIndex=1396|IndexInSheet=21|OwnerPartId=-1|Location.X=223|Location.Y=881|Color=8388608|FontID=1|IsHidden=T|Text=Tape and Reel|Name=Packaging
|RECORD=41|OwnerIndex=1396|IndexInSheet=22|OwnerPartId=-1|Location.X=223|Location.Y=881|Color=8388608|FontID=1|IsHidden=T|Text=6.25mm|Name=Width
|RECORD=41|OwnerIndex=1396|IndexInSheet=23|OwnerPartId=-1|Location.X=223|Location.Y=881|Color=8388608|FontID=1|IsHidden=T|Text=-|Name=Series
|RECORD=41|OwnerIndex=1396|IndexInSheet=24|OwnerPartId=-1|Location.X=223|Location.Y=881|Color=8388608|FontID=1|IsHidden=T|Text=150A|Name=Peak Non-Repetitive Surge Current
|RECORD=41|OwnerIndex=1396|IndexInSheet=25|OwnerPartId=-1|Location.X=223|Location.Y=881|Color=8388608|FontID=1|IsHidden=T|Text=220uA|Name=Max Reverse Leakage Current
|RECORD=41|OwnerIndex=1396|IndexInSheet=26|OwnerPartId=-1|Location.X=223|Location.Y=881|Color=8388608|FontID=1|IsHidden=T|Text=5A|Name=Average Rectified Current
|RECORD=41|OwnerIndex=1396|IndexInSheet=27|OwnerPartId=-1|Location.X=223|Location.Y=881|Color=8388608|FontID=1|IsHidden=T|Text=150A|Name=Max Surge Current
|RECORD=41|OwnerIndex=1396|IndexInSheet=28|OwnerPartId=-1|Location.X=223|Location.Y=881|Color=8388608|FontID=1|IsHidden=T|Text=SMC|Name=Case/Package
|RECORD=41|OwnerIndex=1396|IndexInSheet=29|OwnerPartId=-1|Location.X=223|Location.Y=881|Color=8388608|FontID=1|IsHidden=T|Text=Lead Free|Name=Lead Free
|RECORD=41|OwnerIndex=1396|IndexInSheet=30|OwnerPartId=-1|Location.X=223|Location.Y=881|Color=8388608|FontID=1|IsHidden=T|Text=60V|Name=Max Repetitive Reverse Voltage (Vrrm)
|RECORD=41|OwnerIndex=1396|IndexInSheet=31|OwnerPartId=-1|Location.X=223|Location.Y=881|Color=8388608|FontID=1|IsHidden=T|Text=-65°C|Name=Min Operating Temperature
|RECORD=41|OwnerIndex=1396|IndexInSheet=32|OwnerPartId=-1|Location.X=223|Location.Y=881|Color=8388608|FontID=1|IsHidden=T|Text=520mV|Name=Forward Voltage
|RECORD=41|OwnerIndex=1396|IndexInSheet=33|OwnerPartId=-1|Location.X=223|Location.Y=881|Color=8388608|FontID=1|IsHidden=T|Text=Yes|Name=RoHS Compliant
|RECORD=41|OwnerIndex=1396|IndexInSheet=34|OwnerPartId=-1|Location.X=223|Location.Y=881|Color=8388608|FontID=1|IsHidden=T|Text=Single|Name=Element Configuration
|RECORD=41|OwnerIndex=1396|IndexInSheet=35|OwnerPartId=-1|Location.X=223|Location.Y=881|Color=8388608|FontID=1|IsHidden=T|Text=7.15mm|Name=Length
|RECORD=41|OwnerIndex=1396|IndexInSheet=36|OwnerPartId=-1|Location.X=223|Location.Y=881|Color=8388608|FontID=1|IsHidden=T|Text=220uA|Name=Max Reverse Current
|RECORD=41|OwnerIndex=1396|IndexInSheet=37|OwnerPartId=-1|Location.X=223|Location.Y=881|Color=8388608|FontID=1|IsHidden=T|Text=150°C|Name=Max Operating Temperature
|RECORD=34|OwnerIndex=1396|IndexInSheet=-1|OwnerPartId=-1|Location.X=241|Location.Y=881|Color=8388608|FontID=1|Text=D12|Name=Designator|ReadOnlyState=1
|RECORD=41|OwnerIndex=1396|IndexInSheet=-1|OwnerPartId=1|Location.X=241|Location.Y=849|Color=8388608|FontID=1|Text=STPS5L60S|Name=Comment
|RECORD=44|OwnerIndex=1396
|RECORD=45|OwnerIndex=1439|IndexInSheet=-1|UseComponentLibrary=T|ModelName=FP-STPS5L60S-MFG|ModelType=PCBLIB|IsCurrent=T|DatalinksLocked=T|DatabaseDatalinksLocked=T
|RECORD=46|OwnerIndex=1440
|RECORD=48|OwnerIndex=1440
|RECORD=27|IndexInSheet=89|OwnerPartId=-1|LineWidth=1|Color=8388608|LocationCount=4|X1=580|Y1=770|X2=580|Y2=730|X3=530|Y3=730|X4=530|Y4=910
|RECORD=27|IndexInSheet=90|OwnerPartId=-1|LineWidth=1|Color=8388608|LocationCount=5|X1=690|Y1=930|X2=690|Y2=960|X3=590|Y3=960|X4=530|Y4=960|X5=530|Y5=940
|RECORD=27|IndexInSheet=91|OwnerPartId=-1|LineWidth=1|Color=8388608|LocationCount=3|X1=690|Y1=780|X2=690|Y2=730|X3=580|Y3=730
|RECORD=27|IndexInSheet=92|OwnerPartId=-1|LineWidth=1|Color=8388608|LocationCount=3|X1=630|Y1=840|X2=580|Y2=840|X3=580|Y3=800
|RECORD=27|IndexInSheet=93|OwnerPartId=-1|LineWidth=1|Color=8388608|LocationCount=3|X1=590|Y1=900|X2=590|Y2=870|X3=630|Y3=870
|RECORD=27|IndexInSheet=94|OwnerPartId=-1|LineWidth=1|Color=8388608|LocationCount=3|X1=740|Y1=930|X2=740|Y2=960|X3=800|Y3=960
|RECORD=27|IndexInSheet=95|OwnerPartId=-1|LineWidth=1|Color=8388608|LocationCount=3|X1=800|Y1=840|X2=860|Y2=840|X3=870|Y3=840
|RECORD=27|IndexInSheet=96|OwnerPartId=-1|LineWidth=1|Color=8388608|LocationCount=4|X1=830|Y1=960|X2=850|Y2=960|X3=850|Y3=870|X4=800|Y4=870
|RECORD=27|IndexInSheet=97|OwnerPartId=-1|LineWidth=1|Color=8388608|LocationCount=7|X1=860|Y1=760|X2=860|Y2=730|X3=980|Y3=730|X4=1030|Y4=730|X5=1080|Y5=730|X6=1130|Y6=730|X7=1180|Y7=730
|RECORD=27|IndexInSheet=98|OwnerPartId=-1|LineWidth=1|Color=8388608|LocationCount=7|X1=920|Y1=840|X2=930|Y2=840|X3=980|Y3=840|X4=1030|Y4=840|X5=1080|Y5=840|X6=1130|Y6=840|X7=1180|Y7=840
|RECORD=27|IndexInSheet=99|OwnerPartId=-1|LineWidth=1|Color=8388608|LocationCount=4|X1=422|Y1=717|X2=422|Y2=707|X3=472|Y3=707|X4=472|Y4=697
|RECORD=27|IndexInSheet=100|OwnerPartId=-1|LineWidth=1|Color=8388608|LocationCount=3|X1=1180|Y1=730|X2=1230|Y2=730|X3=1230|Y3=780
|RECORD=27|IndexInSheet=101|OwnerPartId=-1|LineWidth=1|Color=8388608|LocationCount=3|X1=1180|Y1=840|X2=1230|Y2=840|X3=1230|Y3=810
|RECORD=27|IndexInSheet=102|OwnerPartId=-1|LineWidth=1|Color=8388608|LocationCount=5|X1=670|Y1=370|X2=670|Y2=280|X3=590|Y3=280|X4=530|Y4=280|X5=530|Y5=510
|RECORD=27|IndexInSheet=103|OwnerPartId=-1|LineWidth=1|Color=8388608|LocationCount=5|X1=670|Y1=520|X2=670|Y2=560|X3=590|Y3=560|X4=530|Y4=560|X5=530|Y5=540
|RECORD=27|IndexInSheet=104|OwnerPartId=-1|LineWidth=1|Color=8388608|LocationCount=3|X1=610|Y1=430|X2=590|Y2=430|X3=590|Y3=360
|RECORD=27|IndexInSheet=105|OwnerPartId=-1|LineWidth=1|Color=8388608|LocationCount=3|X1=610|Y1=460|X2=590|Y2=460|X3=590|Y3=490
|RECORD=27|IndexInSheet=106|OwnerPartId=-1|LineWidth=1|Color=8388608|LocationCount=3|X1=720|Y1=520|X2=720|Y2=560|X3=750|Y3=560
|RECORD=27|IndexInSheet=107|OwnerPartId=-1|LineWidth=1|Color=8388608|LocationCount=2|X1=810|Y1=430|X2=780|Y2=430
|RECORD=27|IndexInSheet=108|OwnerPartId=-1|LineWidth=1|Color=8388608|LocationCount=4|X1=780|Y1=560|X2=810|Y2=560|X3=810|Y3=460|X4=780|Y4=460
|RECORD=27|IndexInSheet=109|OwnerPartId=-1|LineWidth=1|Color=8388608|LocationCount=7|X1=1120|Y1=380|X2=1120|Y2=280|X3=1070|Y3=280|X4=1020|Y4=280|X5=970|Y5=280|X6=810|Y6=280|X7=810|Y7=310
|RECORD=27|IndexInSheet=110|OwnerPartId=-1|LineWidth=1|Color=8388608|LocationCount=3|X1=870|Y1=430|X2=810|Y2=430|X3=810|Y3=360
|RECORD=27|IndexInSheet=111|OwnerPartId=-1|LineWidth=1|Color=8388608|LocationCount=2|X1=810|Y1=460|X2=850|Y2=460
|RECORD=27|IndexInSheet=112|OwnerPartId=-1|LineWidth=1|Color=8388608|LocationCount=2|X1=920|Y1=430|X2=970|Y2=430
|RECORD=27|IndexInSheet=113|OwnerPartId=-1|LineWidth=1|Color=8388608|LocationCount=3|X1=930|Y1=460|X2=970|Y2=460|X3=970|Y3=430
|RECORD=27|IndexInSheet=114|OwnerPartId=-1|LineWidth=1|Color=8388608|LocationCount=5|X1=970|Y1=430|X2=1020|Y2=430|X3=1070|Y3=430|X4=1120|Y4=430|X5=1120|Y5=410
|RECORD=27|IndexInSheet=115|OwnerPartId=-1|LineWidth=1|Color=8388608|LocationCount=4|X1=1220|Y1=380|X2=1220|Y2=280|X3=1170|Y3=280|X4=1120|Y4=280
|RECORD=27|IndexInSheet=116|OwnerPartId=-1|LineWidth=1|Color=8388608|LocationCount=4|X1=1120|Y1=430|X2=1170|Y2=430|X3=1220|Y3=430|X4=1220|Y4=410
|RECORD=27|IndexInSheet=117|OwnerPartId=-1|LineWidth=1|Color=8388608|LocationCount=2|X1=590|Y1=950|X2=590|Y2=960
|RECORD=27|IndexInSheet=118|OwnerPartId=-1|LineWidth=1|Color=8388608|LocationCount=2|X1=740|Y1=730|X2=740|Y2=740
|RECORD=27|IndexInSheet=119|OwnerPartId=-1|LineWidth=1|Color=8388608|LocationCount=2|X1=740|Y1=770|X2=740|Y2=780
|RECORD=27|IndexInSheet=120|OwnerPartId=-1|LineWidth=1|Color=8388608|LocationCount=2|X1=860|Y1=840|X2=860|Y2=810
|RECORD=27|IndexInSheet=121|OwnerPartId=-1|LineWidth=1|Color=8388608|LocationCount=2|X1=930|Y1=870|X2=930|Y2=840
|RECORD=27|IndexInSheet=122|OwnerPartId=-1|LineWidth=1|Color=8388608|LocationCount=2|X1=930|Y1=950|X2=930|Y2=870
|RECORD=27|IndexInSheet=123|OwnerPartId=-1|LineWidth=1|Color=8388608|LocationCount=2|X1=980|Y1=780|X2=980|Y2=730
|RECORD=27|IndexInSheet=124|OwnerPartId=-1|LineWidth=1|Color=8388608|LocationCount=2|X1=980|Y1=810|X2=980|Y2=840
|RECORD=27|IndexInSheet=125|OwnerPartId=-1|LineWidth=1|Color=8388608|LocationCount=2|X1=1030|Y1=780|X2=1030|Y2=730
|RECORD=27|IndexInSheet=126|OwnerPartId=-1|LineWidth=1|Color=8388608|LocationCount=2|X1=1030|Y1=810|X2=1030|Y2=840
|RECORD=27|IndexInSheet=127|OwnerPartId=-1|LineWidth=1|Color=8388608|LocationCount=2|X1=1080|Y1=780|X2=1080|Y2=730
|RECORD=27|IndexInSheet=128|OwnerPartId=-1|LineWidth=1|Color=8388608|LocationCount=2|X1=1080|Y1=840|X2=1080|Y2=810
|RECORD=27|IndexInSheet=129|OwnerPartId=-1|LineWidth=1|Color=8388608|LocationCount=2|X1=1130|Y1=780|X2=1130|Y2=730
|RECORD=27|IndexInSheet=130|OwnerPartId=-1|LineWidth=1|Color=8388608|LocationCount=2|X1=1130|Y1=810|X2=1130|Y2=840
|RECORD=27|IndexInSheet=131|OwnerPartId=-1|LineWidth=1|Color=8388608|LocationCount=2|X1=472|Y1=717|X2=472|Y2=707
|RECORD=27|IndexInSheet=132|OwnerPartId=-1|LineWidth=1|Color=8388608|LocationCount=2|X1=472|Y1=787|X2=472|Y2=807
|RECORD=27|IndexInSheet=133|OwnerPartId=-1|LineWidth=1|Color=8388608|LocationCount=2|X1=1180|Y1=780|X2=1180|Y2=730
|RECORD=27|IndexInSheet=134|OwnerPartId=-1|LineWidth=1|Color=8388608|LocationCount=2|X1=1180|Y1=810|X2=1180|Y2=840
|RECORD=27|IndexInSheet=135|OwnerPartId=-1|LineWidth=1|Color=8388608|LocationCount=2|X1=590|Y1=330|X2=590|Y2=280
|RECORD=27|IndexInSheet=136|OwnerPartId=-1|LineWidth=1|Color=8388608|LocationCount=2|X1=590|Y1=540|X2=590|Y2=560
|RECORD=27|IndexInSheet=137|OwnerPartId=-1|LineWidth=1|Color=8388608|LocationCount=2|X1=720|Y1=280|X2=720|Y2=300
|RECORD=27|IndexInSheet=138|OwnerPartId=-1|LineWidth=1|Color=8388608|LocationCount=2|X1=720|Y1=330|X2=720|Y2=370
|RECORD=27|IndexInSheet=139|OwnerPartId=-1|LineWidth=1|Color=8388608|LocationCount=2|X1=970|Y1=380|X2=970|Y2=280
|RECORD=27|IndexInSheet=140|OwnerPartId=-1|LineWidth=1|Color=8388608|LocationCount=2|X1=970|Y1=410|X2=970|Y2=430
|RECORD=27|IndexInSheet=141|OwnerPartId=-1|LineWidth=1|Color=8388608|LocationCount=2|X1=970|Y1=460|X2=970|Y2=550
|RECORD=27|IndexInSheet=142|OwnerPartId=-1|LineWidth=1|Color=8388608|LocationCount=2|X1=1020|Y1=380|X2=1020|Y2=280
|RECORD=27|IndexInSheet=143|OwnerPartId=-1|LineWidth=1|Color=8388608|LocationCount=2|X1=1020|Y1=410|X2=1020|Y2=430
|RECORD=27|IndexInSheet=144|OwnerPartId=-1|LineWidth=1|Color=8388608|LocationCount=2|X1=1070|Y1=380|X2=1070|Y2=280
|RECORD=27|IndexInSheet=145|OwnerPartId=-1|LineWidth=1|Color=8388608|LocationCount=2|X1=1070|Y1=410|X2=1070|Y2=430
|RECORD=27|IndexInSheet=146|OwnerPartId=-1|LineWidth=1|Color=8388608|LocationCount=2|X1=1170|Y1=380|X2=1170|Y2=280
|RECORD=27|IndexInSheet=147|OwnerPartId=-1|LineWidth=1|Color=8388608|LocationCount=2|X1=1170|Y1=410|X2=1170|Y2=430
|RECORD=27|IndexInSheet=148|OwnerPartId=-1|LineWidth=1|Color=8388608|LocationCount=2|X1=1330|Y1=300|X2=1330|Y2=280
|RECORD=27|IndexInSheet=149|OwnerPartId=-1|LineWidth=1|Color=8388608|LocationCount=2|X1=1330|Y1=370|X2=1330|Y2=350
|RECORD=27|IndexInSheet=150|OwnerPartId=-1|LineWidth=1|Color=8388608|LocationCount=2|X1=1330|Y1=430|X2=1330|Y2=440
|RECORD=27|IndexInSheet=151|OwnerPartId=-1|LineWidth=1|Color=8388608|LocationCount=2|X1=175|Y1=823|X2=125|Y2=823
|RECORD=27|IndexInSheet=152|OwnerPartId=-1|LineWidth=1|Color=8388608|LocationCount=2|X1=125|Y1=813|X2=175|Y2=813
|RECORD=27|IndexInSheet=153|OwnerPartId=-1|LineWidth=1|Color=8388608|LocationCount=2|X1=175|Y1=853|X2=125|Y2=853
|RECORD=27|IndexInSheet=154|OwnerPartId=-1|LineWidth=1|Color=8388608|LocationCount=5|X1=125|Y1=833|X2=175|Y2=833|X3=175|Y3=823|X4=175|Y4=813|X5=175|Y5=783
|RECORD=27|IndexInSheet=155|OwnerPartId=-1|LineWidth=1|Color=8388608|LocationCount=4|X1=125|Y1=843|X2=175|Y2=843|X3=175|Y3=853|X4=175|Y4=863
|RECORD=27|IndexInSheet=156|OwnerPartId=-1|LineWidth=1|Color=8388608|LocationCount=4|X1=125|Y1=863|X2=175|Y2=863|X3=175|Y3=870|X4=225|Y4=870
|RECORD=27|IndexInSheet=157|OwnerPartId=-1|LineWidth=1|Color=8388608|LocationCount=3|X1=385|Y1=785|X2=410|Y2=785|X3=422|Y3=785
|RECORD=27|IndexInSheet=158|OwnerPartId=-1|LineWidth=1|Color=8388608|LocationCount=5|X1=325|Y1=785|X2=290|Y2=785|X3=290|Y3=825|X4=290|Y4=870|X5=285|Y5=870
|RECORD=27|IndexInSheet=159|OwnerPartId=-1|LineWidth=1|Color=8388608|LocationCount=5|X1=422|Y1=747|X2=422|Y2=785|X3=422|Y3=787|X4=472|Y4=787|X5=472|Y5=747
|RECORD=1|LibReference=1d6ec82d83fb6aee721767c19dac4b9|ComponentDescription=DIODE SCHOTTKY 60V 5A SMC|PartCount=2|DisplayModeCount=1|IndexInSheet=160|OwnerPartId=-1|Location.X=140|Location.Y=700|CurrentPartId=1|LibraryPath=*|SourceLibraryName=Altium Content Vault|TargetFileName=*|AreaColor=11599871|Color=128|PartIDLocked=T|DesignItemId=CMP-12187-000009-2|AllPinCount=2
|RECORD=2|OwnerIndex=1514|OwnerPartId=1|Electrical=4|PinConglomerate=50|PinLength=20|Location.X=160|Location.Y=700|Name=A|Designator=2|PinPropagationDelay=0.000000E+000
|RECORD=2|OwnerIndex=1514|OwnerPartId=1|Electrical=4|PinConglomerate=48|PinLength=20|Location.X=180|Location.Y=700|Name=C|Designator=1|PinPropagationDelay=0.000000E+000
|RECORD=13|OwnerIndex=1514|IsNotAccesible=T|IndexInSheet=2|OwnerPartId=1|Location.X=160|Location.Y=710|Corner.X=160|Corner.Y=690|LineWidth=1|Color=16711680
|RECORD=13|OwnerIndex=1514|IsNotAccesible=T|IndexInSheet=3|OwnerPartId=1|Location.X=180|Location.Y=710|Corner.X=180|Corner.Y=690|LineWidth=1|Color=16711680
|RECORD=13|OwnerIndex=1514|IsNotAccesible=T|IndexInSheet=4|OwnerPartId=1|Location.X=160|Location.Y=710|Corner.X=180|Corner.Y=700|LineWidth=1|Color=16711680
|RECORD=13|OwnerIndex=1514|IsNotAccesible=T|IndexInSheet=5|OwnerPartId=1|Location.X=160|Location.Y=690|Corner.X=180|Corner.Y=700|LineWidth=1|Color=16711680
|RECORD=13|OwnerIndex=1514|IsNotAccesible=T|IndexInSheet=6|OwnerPartId=1|Location.X=180|Location.Y=710|Corner.X=177|Corner.Y=710|LineWidth=1|Color=16711680
|RECORD=13|OwnerIndex=1514|IsNotAccesible=T|IndexInSheet=7|OwnerPartId=1|Location.X=183|Location.Y=690|Corner.X=183|Corner.Y=693|LineWidth=1|Color=16711680
|RECORD=13|OwnerIndex=1514|IsNotAccesible=T|IndexInSheet=8|OwnerPartId=1|Location.X=177|Location.Y=710|Corner.X=177|Corner.Y=707|LineWidth=1|Color=16711680
|RECORD=13|OwnerIndex=1514|IsNotAccesible=T|IndexInSheet=9|OwnerPartId=1|Location.X=180|Location.Y=690|Corner.X=183|Corner.Y=690|LineWidth=1|Color=16711680
|RECORD=13|OwnerIndex=1514|IsNotAccesible=T|IndexInSheet=10|OwnerPartId=1|Location.X=160|Location.Y=700|Corner.X=157|Corner.Y=700|LineWidth=1|Color=16711680
|RECORD=13|OwnerIndex=1514|IsNotAccesible=T|IndexInSheet=11|OwnerPartId=1|Location.X=180|Location.Y=700|Corner.X=183|Corner.Y=700|LineWidth=1|Color=16711680
|RECORD=41|OwnerIndex=1514|IndexInSheet=12|OwnerPartId=-1|Location.X=138|Location.Y=711|Color=8388608|FontID=1|IsHidden=T|Text=No|Name=Radiation Hardening
|RECORD=41|OwnerIndex=1514|IndexInSheet=13|OwnerPartId=-1|Location.X=138|Location.Y=711|Color=8388608|FontID=1|IsHidden=T|Text=150A|Name=Max Forward Surge Current (Ifsm)
|RECORD=41|OwnerIndex=1514|IndexInSheet=14|OwnerPartId=-1|Location.X=138|Location.Y=711|Color=8388608|FontID=1|IsHidden=T|Text=2500|Name=Package Quantity
|RECORD=41|OwnerIndex=1514|IndexInSheet=15|OwnerPartId=-1|Location.X=138|Location.Y=711|Color=8388608|FontID=1|IsHidden=T|Text=No SVHC|Name=REACH SVHC
|RECORD=41|OwnerIndex=1514|IndexInSheet=16|OwnerPartId=-1|Location.X=138|Location.Y=711|Color=8388608|FontID=1|IsHidden=T|Text=60V|Name=Max Reverse Voltage (DC)
|RECORD=41|OwnerIndex=1514|IndexInSheet=17|OwnerPartId=-1|Location.X=138|Location.Y=711|Color=8388608|FontID=1|IsHidden=T|Text=2|Name=Number of Pins
|RECORD=41|OwnerIndex=1514|IndexInSheet=18|OwnerPartId=-1|Location.X=138|Location.Y=711|Color=8388608|FontID=1|IsHidden=T|Text=Surface Mount|Name=Mount
|RECORD=41|OwnerIndex=1514|IndexInSheet=19|OwnerPartId=-1|Location.X=138|Location.Y=711|Color=8388608|FontID=1|IsHidden=T|Text=2.45mm|Name=Height
|RECORD=41|OwnerIndex=1514|IndexInSheet=20|OwnerPartId=-1|Location.X=138|Location.Y=711|Color=8388608|FontID=1|IsHidden=T|Text=5A|Name=Forward Current
|RECORD=41|OwnerIndex=1514|IndexInSheet=21|OwnerPartId=-1|Location.X=138|Location.Y=711|Color=8388608|FontID=1|IsHidden=T|Text=Tape and Reel|Name=Packaging
|RECORD=41|OwnerIndex=1514|IndexInSheet=22|OwnerPartId=-1|Location.X=138|Location.Y=711|Color=8388608|FontID=1|IsHidden=T|Text=6.25mm|Name=Width
|RECORD=41|OwnerIndex=1514|IndexInSheet=23|OwnerPartId=-1|Location.X=138|Location.Y=711|Color=8388608|FontID=1|IsHidden=T|Text=-|Name=Series
|RECORD=41|OwnerIndex=1514|IndexInSheet=24|OwnerPartId=-1|Location.X=138|Location.Y=711|Color=8388608|FontID=1|IsHidden=T|Text=150A|Name=Peak Non-Repetitive Surge Current
|RECORD=41|OwnerIndex=1514|IndexInSheet=25|OwnerPartId=-1|Location.X=138|Location.Y=711|Color=8388608|FontID=1|IsHidden=T|Text=220uA|Name=Max Reverse Leakage Current
|RECORD=41|OwnerIndex=1514|IndexInSheet=26|OwnerPartId=-1|Location.X=138|Location.Y=711|Color=8388608|FontID=1|IsHidden=T|Text=5A|Name=Average Rectified Current
|RECORD=41|OwnerIndex=1514|IndexInSheet=27|OwnerPartId=-1|Location.X=138|Location.Y=711|Color=8388608|FontID=1|IsHidden=T|Text=150A|Name=Max Surge Current
|RECORD=41|OwnerIndex=1514|IndexInSheet=28|OwnerPartId=-1|Location.X=138|Location.Y=711|Color=8388608|FontID=1|IsHidden=T|Text=SMC|Name=Case/Package
|RECORD=41|OwnerIndex=1514|IndexInSheet=29|OwnerPartId=-1|Location.X=138|Location.Y=711|Color=8388608|FontID=1|IsHidden=T|Text=Lead Free|Name=Lead Free
|RECORD=41|OwnerIndex=1514|IndexInSheet=30|OwnerPartId=-1|Location.X=138|Location.Y=711|Color=8388608|FontID=1|IsHidden=T|Text=60V|Name=Max Repetitive Reverse Voltage (Vrrm)
|RECORD=41|OwnerIndex=1514|IndexInSheet=31|OwnerPartId=-1|Location.X=138|Location.Y=711|Color=8388608|FontID=1|IsHidden=T|Text=-65°C|Name=Min Operating Temperature
|RECORD=41|OwnerIndex=1514|IndexInSheet=32|OwnerPartId=-1|Location.X=138|Location.Y=711|Color=8388608|FontID=1|IsHidden=T|Text=520mV|Name=Forward Voltage
|RECORD=41|OwnerIndex=1514|IndexInSheet=33|OwnerPartId=-1|Location.X=138|Location.Y=711|Color=8388608|FontID=1|IsHidden=T|Text=Yes|Name=RoHS Compliant
|RECORD=41|OwnerIndex=1514|IndexInSheet=34|OwnerPartId=-1|Location.X=138|Location.Y=711|Color=8388608|FontID=1|IsHidden=T|Text=Single|Name=Element Configuration
|RECORD=41|OwnerIndex=1514|IndexInSheet=35|OwnerPartId=-1|Location.X=138|Location.Y=711|Color=8388608|FontID=1|IsHidden=T|Text=7.15mm|Name=Length
|RECORD=41|OwnerIndex=1514|IndexInSheet=36|OwnerPartId=-1|Location.X=138|Location.Y=711|Color=8388608|FontID=1|IsHidden=T|Text=220uA|Name=Max Reverse Current
|RECORD=41|OwnerIndex=1514|IndexInSheet=37|OwnerPartId=-1|Location.X=138|Location.Y=711|Color=8388608|FontID=1|IsHidden=T|Text=150°C|Name=Max Operating Temperature
|RECORD=34|OwnerIndex=1514|IndexInSheet=-1|OwnerPartId=-1|Location.X=156|Location.Y=711|Color=8388608|FontID=1|Text=D19|Name=Designator|ReadOnlyState=1
|RECORD=41|OwnerIndex=1514|IndexInSheet=-1|OwnerPartId=1|Location.X=156|Location.Y=679|Color=8388608|FontID=1|Text=STPS5L60S|Name=Comment
|RECORD=44|OwnerIndex=1514
|RECORD=45|OwnerIndex=1557|IndexInSheet=-1|UseComponentLibrary=T|ModelName=FP-STPS5L60S-MFG|ModelType=PCBLIB|IsCurrent=T|DatalinksLocked=T|DatabaseDatalinksLocked=T
|RECORD=46|OwnerIndex=1558
|RECORD=48|OwnerIndex=1558
|RECORD=27|IndexInSheet=161|OwnerPartId=-1|LineWidth=1|Color=8388608|LocationCount=5|X1=200|Y1=700|X2=207|Y2=700|X3=207|Y3=699|X4=290|Y4=699|X5=290|Y5=785
|RECORD=27|IndexInSheet=162|OwnerPartId=-1|LineWidth=1|Color=8388608|LocationCount=3|X1=140|Y1=700|X2=87|Y2=700|X3=87|Y3=709
|RECORD=1|LibReference=RES|PartCount=2|DisplayModeCount=2|IndexInSheet=163|OwnerPartId=-1|Location.X=340|Location.Y=835|CurrentPartId=1|SourceLibraryName=Altium Content Vault|TargetFileName=*|AreaColor=11599871|Color=128|PartIDLocked=F|DesignItemId=CMP-2003-04873-1|AllPinCount=2|ComponentKindVersion2=5
|RECORD=2|OwnerIndex=1563|OwnerPartId=1|OwnerPartDisplayMode=1|FormalType=1|Electrical=4|PinConglomerate=32|PinLength=10|Location.X=360|Location.Y=825|Name=2|Designator=2|PinPropagationDelay=0.000000E+000
|RECORD=2|OwnerIndex=1563|OwnerPartId=1|OwnerPartDisplayMode=1|FormalType=1|Electrical=4|PinConglomerate=34|PinLength=10|Location.X=340|Location.Y=825|Name=1|Designator=1|PinPropagationDelay=0.000000E+000
|RECORD=14|OwnerIndex=1563|IsNotAccesible=T|IndexInSheet=2|OwnerPartId=1|OwnerPartDisplayMode=1|Location.X=340|Location.Y=821|Corner.X=360|Corner.Y=829|LineWidth=1|Color=16711680|AreaColor=11599871
|RECORD=2|OwnerIndex=1563|OwnerPartId=1|FormalType=1|Electrical=4|PinConglomerate=32|PinLength=10|Location.X=360|Location.Y=825|Name=2|Designator=2|PinPropagationDelay=0.000000E+000
|RECORD=2|OwnerIndex=1563|OwnerPartId=1|FormalType=1|Electrical=4|PinConglomerate=34|PinLength=10|Location.X=340|Location.Y=825|Name=1|Designator=1|PinPropagationDelay=0.000000E+000
|RECORD=6|OwnerIndex=1563|IsNotAccesible=T|IndexInSheet=5|OwnerPartId=1|LineWidth=1|Color=16711680|LocationCount=10|X1=360|Y1=825|X2=356|Y2=825|X3=355|Y3=823|X4=353|Y4=827|X5=351|Y5=823|X6=349|Y6=827|X7=347|Y7=823|X8=345|Y8=827|X9=344|Y9=825|X10=340|Y10=825
|RECORD=41|OwnerIndex=1563|IndexInSheet=6|OwnerPartId=-1|Location.X=328|Location.Y=838|Color=8388608|FontID=1|IsHidden=T|Text=CRCW12060000Z0EAHP|Name=Part Number
|RECORD=41|OwnerIndex=1563|IndexInSheet=7|OwnerPartId=-1|Location.X=328|Location.Y=838|Color=8388608|FontID=1|IsHidden=T|Text=Vishay Dale|Name=Manufacturer
|RECORD=34|OwnerIndex=1563|IndexInSheet=-1|OwnerPartId=-1|Location.X=339|Location.Y=828|Color=8388608|FontID=1|Text=R44|Name=Designator|ReadOnlyState=1
|RECORD=41|OwnerIndex=1563|IndexInSheet=-1|OwnerPartId=-1|Location.X=339|Location.Y=812|Color=8388608|FontID=1|Text=DNI_0_5%_1206|Name=Comment
|RECORD=44|OwnerIndex=1563
|RECORD=45|OwnerIndex=1578|IndexInSheet=-1|Description=Chip Resistor, 2-Leads, Body 3.10x1.60mm, IPC Low Density|UseComponentLibrary=T|ModelName=RESC3116X65X50ML20T20|ModelType=PCBLIB|IsCurrent=T|DatalinksLocked=T|DatabaseDatalinksLocked=T
|RECORD=46|OwnerIndex=1579
|RECORD=48|OwnerIndex=1579
|RECORD=41|OwnerIndex=1581|IndexInSheet=-1|OwnerPartId=-1|Color=8388608|FontID=1|IsHidden=T|Text=2D|Name=Available Preview Images
|RECORD=45|OwnerIndex=1578|IndexInSheet=-1|Description=Chip Resistor, 2-Leads, Body 3.10x1.60mm, IPC High Density|UseComponentLibrary=T|ModelName=RESC3116X65X50LL20T20|ModelType=PCBLIB|DatalinksLocked=T|DatabaseDatalinksLocked=T
|RECORD=46|OwnerIndex=1583
|RECORD=48|OwnerIndex=1583
|RECORD=41|OwnerIndex=1585|IndexInSheet=-1|OwnerPartId=-1|Color=8388608|FontID=1|IsHidden=T|Text=2D|Name=Available Preview Images
|RECORD=45|OwnerIndex=1578|IndexInSheet=-1|Description=Chip Resistor, 2-Leads, Body 3.10x1.60mm, IPC Medium Density|UseComponentLibrary=T|ModelName=RESC3116X65X50NL20T20|ModelType=PCBLIB|DatalinksLocked=T|DatabaseDatalinksLocked=T
|RECORD=46|OwnerIndex=1587
|RECORD=48|OwnerIndex=1587
|RECORD=41|OwnerIndex=1589|IndexInSheet=-1|OwnerPartId=-1|Color=8388608|FontID=1|IsHidden=T|Text=2D|Name=Available Preview Images
|RECORD=27|IndexInSheet=164|OwnerPartId=-1|LineWidth=1|Color=8388608|LocationCount=3|X1=370|Y1=825|X2=410|Y2=825|X3=410|Y3=785
|RECORD=27|IndexInSheet=165|OwnerPartId=-1|LineWidth=1|Color=8388608|LocationCount=2|X1=330|Y1=825|X2=290|Y2=825
|RECORD=29|IndexInSheet=-1|OwnerPartId=-1|Location.X=175|Location.Y=813|Color=128
|RECORD=29|IndexInSheet=-1|OwnerPartId=-1|Location.X=175|Location.Y=823|Color=128
|RECORD=29|IndexInSheet=-1|OwnerPartId=-1|Location.X=175|Location.Y=853|Color=128
|RECORD=29|IndexInSheet=-1|OwnerPartId=-1|Location.X=175|Location.Y=863|Color=128
|RECORD=29|IndexInSheet=-1|OwnerPartId=-1|Location.X=290|Location.Y=785|Color=128
|RECORD=29|IndexInSheet=-1|OwnerPartId=-1|Location.X=290|Location.Y=825|Color=128
|RECORD=29|IndexInSheet=-1|OwnerPartId=-1|Location.X=410|Location.Y=785|Color=128
|RECORD=29|IndexInSheet=-1|OwnerPartId=-1|Location.X=422|Location.Y=785|Color=128
|RECORD=29|IndexInSheet=-1|OwnerPartId=-1|Location.X=472|Location.Y=707|Color=128
|RECORD=29|IndexInSheet=-1|OwnerPartId=-1|Location.X=472|Location.Y=787|Color=128
|RECORD=29|IndexInSheet=-1|OwnerPartId=-1|Location.X=530|Location.Y=280|Color=128
|RECORD=29|IndexInSheet=-1|OwnerPartId=-1|Location.X=530|Location.Y=560|Color=128
|RECORD=29|IndexInSheet=-1|OwnerPartId=-1|Location.X=530|Location.Y=960|Color=128
|RECORD=29|IndexInSheet=-1|OwnerPartId=-1|Location.X=580|Location.Y=730|Color=128
|RECORD=29|IndexInSheet=-1|OwnerPartId=-1|Location.X=590|Location.Y=280|Color=128
|RECORD=29|IndexInSheet=-1|OwnerPartId=-1|Location.X=590|Location.Y=560|Color=128
|RECORD=29|IndexInSheet=-1|OwnerPartId=-1|Location.X=590|Location.Y=960|Color=128
|RECORD=29|IndexInSheet=-1|OwnerPartId=-1|Location.X=670|Location.Y=280|Color=128
|RECORD=29|IndexInSheet=-1|OwnerPartId=-1|Location.X=690|Location.Y=730|Color=128
|RECORD=29|IndexInSheet=-1|OwnerPartId=-1|Location.X=810|Location.Y=280|Color=128
|RECORD=29|IndexInSheet=-1|OwnerPartId=-1|Location.X=810|Location.Y=430|Color=128
|RECORD=29|IndexInSheet=-1|OwnerPartId=-1|Location.X=810|Location.Y=460|Color=128
|RECORD=29|IndexInSheet=-1|OwnerPartId=-1|Location.X=850|Location.Y=870|Color=128
|RECORD=29|IndexInSheet=-1|OwnerPartId=-1|Location.X=860|Location.Y=730|Color=128
|RECORD=29|IndexInSheet=-1|OwnerPartId=-1|Location.X=860|Location.Y=840|Color=128
|RECORD=29|IndexInSheet=-1|OwnerPartId=-1|Location.X=930|Location.Y=840|Color=128
|RECORD=29|IndexInSheet=-1|OwnerPartId=-1|Location.X=930|Location.Y=870|Color=128
|RECORD=29|IndexInSheet=-1|OwnerPartId=-1|Location.X=970|Location.Y=280|Color=128
|RECORD=29|IndexInSheet=-1|OwnerPartId=-1|Location.X=970|Location.Y=430|Color=128
|RECORD=29|IndexInSheet=-1|OwnerPartId=-1|Location.X=970|Location.Y=460|Color=128
|RECORD=29|IndexInSheet=-1|OwnerPartId=-1|Location.X=980|Location.Y=730|Color=128
|RECORD=29|IndexInSheet=-1|OwnerPartId=-1|Location.X=980|Location.Y=840|Color=128
|RECORD=29|IndexInSheet=-1|OwnerPartId=-1|Location.X=1020|Location.Y=280|Color=128
|RECORD=29|IndexInSheet=-1|OwnerPartId=-1|Location.X=1020|Location.Y=430|Color=128
|RECORD=29|IndexInSheet=-1|OwnerPartId=-1|Location.X=1030|Location.Y=730|Color=128
|RECORD=29|IndexInSheet=-1|OwnerPartId=-1|Location.X=1030|Location.Y=840|Color=128
|RECORD=29|IndexInSheet=-1|OwnerPartId=-1|Location.X=1070|Location.Y=280|Color=128
|RECORD=29|IndexInSheet=-1|OwnerPartId=-1|Location.X=1070|Location.Y=430|Color=128
|RECORD=29|IndexInSheet=-1|OwnerPartId=-1|Location.X=1080|Location.Y=730|Color=128
|RECORD=29|IndexInSheet=-1|OwnerPartId=-1|Location.X=1080|Location.Y=840|Color=128
|RECORD=29|IndexInSheet=-1|OwnerPartId=-1|Location.X=1120|Location.Y=280|Color=128
|RECORD=29|IndexInSheet=-1|OwnerPartId=-1|Location.X=1120|Location.Y=430|Color=128
|RECORD=29|IndexInSheet=-1|OwnerPartId=-1|Location.X=1130|Location.Y=730|Color=128
|RECORD=29|IndexInSheet=-1|OwnerPartId=-1|Location.X=1130|Location.Y=840|Color=128
|RECORD=29|IndexInSheet=-1|OwnerPartId=-1|Location.X=1170|Location.Y=280|Color=128
|RECORD=29|IndexInSheet=-1|OwnerPartId=-1|Location.X=1170|Location.Y=430|Color=128
|RECORD=29|IndexInSheet=-1|OwnerPartId=-1|Location.X=1180|Location.Y=730|Color=128
|RECORD=29|IndexInSheet=-1|OwnerPartId=-1|Location.X=1180|Location.Y=840|Color=128